G04 ================== begin FILE IDENTIFICATION RECORD ==================*
G04 Layout Name:  D:/<user>/Wistron_project/16317-1/gbr/16317-1.brd*
G04 Film Name:    L7GND*
G04 File Format:  Gerber RS274X*
G04 File Origin:  Cadence Allegro 16.5-S056*
G04 Origin Date:  Fri Jun 09 15:53:42 2017*
G04 *
G04 Layer:  VIA CLASS/L7GND*
G04 Layer:  PIN/L7GND*
G04 Layer:  ETCH/L7GND*
G04 Layer:  DRAWING FORMAT/LAYER_PCB_STORY*
G04 Layer:  DRAWING FORMAT/LAYER_L7GND*
G04 *
G04 Offset:    (0.00 0.00)*
G04 Mirror:    No*
G04 Mode:      Negative*
G04 Rotation:  0*
G04 FullContactRelief:  No*
G04 UndefLineWidth:     6.00*
G04 ================== end FILE IDENTIFICATION RECORD ====================*
%FSLAX35Y35*MOIN*%
%IR0*IPPOS*OFA0.00000B0.00000*MIA0B0*SFA1.00000B1.00000*%
%ADD35C,.04*%
%ADD12C,.032*%
%ADD34C,.043*%
%ADD22C,.081*%
%ADD16C,.063*%
%ADD15C,.036*%
%ADD20C,.065*%
%ADD18C,.038*%
%ADD36C,.058*%
%AMMACRO32*
4,1,14,.0447,.02349,
.0481,.015371,
.050038,.006785,
.050456,-.002007,
.049341,-.010738,
.046727,-.019143,
.0447,-.02349,
.04839,-.02718,
.052375,-.018364,
.054768,-.00899,
.055497,.000656,
.05454,.010283,
.051926,.019598,
.04839,.02718,
.0447,.02349,
180.*
4,1,14,.02349,-.0447,
.015371,-.0481,
.006785,-.050038,
-.002007,-.050456,
-.010738,-.049341,
-.019143,-.046727,
-.02349,-.0447,
-.02718,-.04839,
-.018364,-.052375,
-.00899,-.054768,
.000656,-.055497,
.010283,-.05454,
.019598,-.051926,
.02718,-.04839,
.02349,-.0447,
180.*
4,1,14,-.0447,-.02349,
-.0481,-.015371,
-.050038,-.006785,
-.050456,.002007,
-.049341,.010738,
-.046727,.019143,
-.0447,.02349,
-.04839,.02718,
-.052375,.018364,
-.054768,.00899,
-.055497,-.000656,
-.05454,-.010283,
-.051926,-.019598,
-.04839,-.02718,
-.0447,-.02349,
180.*
4,1,14,-.02349,.0447,
-.015371,.0481,
-.006785,.050038,
.002007,.050456,
.010738,.049341,
.019143,.046727,
.02349,.0447,
.02718,.04839,
.018364,.052375,
.00899,.054768,
-.000656,.055497,
-.010283,.05454,
-.019598,.051926,
-.02718,.04839,
-.02349,.0447,
180.*
%
%ADD32MACRO32*%
%AMMACRO19*
4,1,15,.00398,.00044,
.003999,.000208,
.004004,-.000025,
.003996,-.000258,
.00398,-.00044,
.00483,-.00129,
.004897,-.001007,
.004947,-.000721,
.004981,-.000432,
.004997,-.000141,
.004997,.000149,
.00498,.00044,
.004946,.000729,
.004895,.001015,
.00483,.00129,
.00398,.00044,
90.*
4,1,15,.00044,-.00398,
.000208,-.003999,
-.000025,-.004004,
-.000258,-.003996,
-.00044,-.00398,
-.00129,-.00483,
-.001007,-.004897,
-.000721,-.004947,
-.000432,-.004981,
-.000141,-.004997,
.000149,-.004997,
.00044,-.00498,
.000729,-.004946,
.001015,-.004895,
.00129,-.00483,
.00044,-.00398,
90.*
4,1,15,-.00398,-.00044,
-.003999,-.000208,
-.004004,.000025,
-.003996,.000258,
-.00398,.00044,
-.00483,.00129,
-.004897,.001007,
-.004947,.000721,
-.004981,.000432,
-.004997,.000141,
-.004997,-.000149,
-.00498,-.00044,
-.004946,-.000729,
-.004895,-.001015,
-.00483,-.00129,
-.00398,-.00044,
90.*
4,1,15,-.00044,.00398,
-.000208,.003999,
.000025,.004004,
.000258,.003996,
.00044,.00398,
.00129,.00483,
.001007,.004897,
.000721,.004947,
.000432,.004981,
.000141,.004997,
-.000149,.004997,
-.00044,.00498,
-.000729,.004946,
-.001015,.004895,
-.00129,.00483,
-.00044,.00398,
90.*
%
%ADD19MACRO19*%
%AMMACRO27*
4,1,15,-.00398,.00044,
-.003999,.000208,
-.004004,-.000025,
-.003996,-.000258,
-.00398,-.00044,
-.00483,-.00129,
-.004897,-.001007,
-.004947,-.000721,
-.004981,-.000432,
-.004997,-.000141,
-.004997,.000149,
-.00498,.00044,
-.004946,.000729,
-.004895,.001015,
-.00483,.00129,
-.00398,.00044,
90.*
4,1,15,-.00044,-.00398,
-.000208,-.003999,
.000025,-.004004,
.000258,-.003996,
.00044,-.00398,
.00129,-.00483,
.001007,-.004897,
.000721,-.004947,
.000432,-.004981,
.000141,-.004997,
-.000149,-.004997,
-.00044,-.00498,
-.000729,-.004946,
-.001015,-.004895,
-.00129,-.00483,
-.00044,-.00398,
90.*
4,1,15,.00398,-.00044,
.003999,-.000208,
.004004,.000025,
.003996,.000258,
.00398,.00044,
.00483,.00129,
.004897,.001007,
.004947,.000721,
.004981,.000432,
.004997,.000141,
.004997,-.000149,
.00498,-.00044,
.004946,-.000729,
.004895,-.001015,
.00483,-.00129,
.00398,-.00044,
90.*
4,1,15,.00044,.00398,
.000208,.003999,
-.000025,.004004,
-.000258,.003996,
-.00044,.00398,
-.00129,.00483,
-.001007,.004897,
-.000721,.004947,
-.000432,.004981,
-.000141,.004997,
.000149,.004997,
.00044,.00498,
.000729,.004946,
.001015,.004895,
.00129,.00483,
.00044,.00398,
90.*
%
%ADD27MACRO27*%
%AMMACRO11*
4,1,15,.00398,.00044,
.003999,.000208,
.004004,-.000025,
.003996,-.000258,
.00398,-.00044,
.00483,-.00129,
.004897,-.001007,
.004947,-.000721,
.004981,-.000432,
.004997,-.000141,
.004997,.000149,
.00498,.00044,
.004946,.000729,
.004895,.001015,
.00483,.00129,
.00398,.00044,
0.0*
4,1,15,.00044,-.00398,
.000208,-.003999,
-.000025,-.004004,
-.000258,-.003996,
-.00044,-.00398,
-.00129,-.00483,
-.001007,-.004897,
-.000721,-.004947,
-.000432,-.004981,
-.000141,-.004997,
.000149,-.004997,
.00044,-.00498,
.000729,-.004946,
.001015,-.004895,
.00129,-.00483,
.00044,-.00398,
0.0*
4,1,15,-.00398,-.00044,
-.003999,-.000208,
-.004004,.000025,
-.003996,.000258,
-.00398,.00044,
-.00483,.00129,
-.004897,.001007,
-.004947,.000721,
-.004981,.000432,
-.004997,.000141,
-.004997,-.000149,
-.00498,-.00044,
-.004946,-.000729,
-.004895,-.001015,
-.00483,-.00129,
-.00398,-.00044,
0.0*
4,1,15,-.00044,.00398,
-.000208,.003999,
.000025,.004004,
.000258,.003996,
.00044,.00398,
.00129,.00483,
.001007,.004897,
.000721,.004947,
.000432,.004981,
.000141,.004997,
-.000149,.004997,
-.00044,.00498,
-.000729,.004946,
-.001015,.004895,
-.00129,.00483,
-.00044,.00398,
0.0*
%
%ADD11MACRO11*%
%AMMACRO14*
4,1,15,-.00398,.00044,
-.003999,.000208,
-.004004,-.000025,
-.003996,-.000258,
-.00398,-.00044,
-.00483,-.00129,
-.004897,-.001007,
-.004947,-.000721,
-.004981,-.000432,
-.004997,-.000141,
-.004997,.000149,
-.00498,.00044,
-.004946,.000729,
-.004895,.001015,
-.00483,.00129,
-.00398,.00044,
0.0*
4,1,15,-.00044,-.00398,
-.000208,-.003999,
.000025,-.004004,
.000258,-.003996,
.00044,-.00398,
.00129,-.00483,
.001007,-.004897,
.000721,-.004947,
.000432,-.004981,
.000141,-.004997,
-.000149,-.004997,
-.00044,-.00498,
-.000729,-.004946,
-.001015,-.004895,
-.00129,-.00483,
-.00044,-.00398,
0.0*
4,1,15,.00398,-.00044,
.003999,-.000208,
.004004,.000025,
.003996,.000258,
.00398,.00044,
.00483,.00129,
.004897,.001007,
.004947,.000721,
.004981,.000432,
.004997,.000141,
.004997,-.000149,
.00498,-.00044,
.004946,-.000729,
.004895,-.001015,
.00483,-.00129,
.00398,-.00044,
0.0*
4,1,15,.00044,.00398,
.000208,.003999,
-.000025,.004004,
-.000258,.003996,
-.00044,.00398,
-.00129,.00483,
-.001007,.004897,
-.000721,.004947,
-.000432,.004981,
-.000141,.004997,
.000149,.004997,
.00044,.00498,
.000729,.004946,
.001015,.004895,
.00129,.00483,
.00044,.00398,
0.0*
%
%ADD14MACRO14*%
%ADD28C,.111*%
%ADD10C,.114*%
%ADD33C,.432*%
%ADD21C,.18*%
%ADD31C,.127*%
%ADD30C,.154*%
%ADD29C,.147*%
%ADD37C,.166*%
%ADD23C,.139*%
%AMMACRO17*
4,1,15,.00398,.00044,
.003999,.000208,
.004004,-.000025,
.003996,-.000258,
.00398,-.00044,
.00483,-.00129,
.004897,-.001007,
.004947,-.000721,
.004981,-.000432,
.004997,-.000141,
.004997,.000149,
.00498,.00044,
.004946,.000729,
.004895,.001015,
.00483,.00129,
.00398,.00044,
270.*
4,1,15,.00044,-.00398,
.000208,-.003999,
-.000025,-.004004,
-.000258,-.003996,
-.00044,-.00398,
-.00129,-.00483,
-.001007,-.004897,
-.000721,-.004947,
-.000432,-.004981,
-.000141,-.004997,
.000149,-.004997,
.00044,-.00498,
.000729,-.004946,
.001015,-.004895,
.00129,-.00483,
.00044,-.00398,
270.*
4,1,15,-.00398,-.00044,
-.003999,-.000208,
-.004004,.000025,
-.003996,.000258,
-.00398,.00044,
-.00483,.00129,
-.004897,.001007,
-.004947,.000721,
-.004981,.000432,
-.004997,.000141,
-.004997,-.000149,
-.00498,-.00044,
-.004946,-.000729,
-.004895,-.001015,
-.00483,-.00129,
-.00398,-.00044,
270.*
4,1,15,-.00044,.00398,
-.000208,.003999,
.000025,.004004,
.000258,.003996,
.00044,.00398,
.00129,.00483,
.001007,.004897,
.000721,.004947,
.000432,.004981,
.000141,.004997,
-.000149,.004997,
-.00044,.00498,
-.000729,.004946,
-.001015,.004895,
-.00129,.00483,
-.00044,.00398,
270.*
%
%ADD17MACRO17*%
%AMMACRO13*
4,1,15,.00398,.00044,
.003999,.000208,
.004004,-.000025,
.003996,-.000258,
.00398,-.00044,
.00483,-.00129,
.004897,-.001007,
.004947,-.000721,
.004981,-.000432,
.004997,-.000141,
.004997,.000149,
.00498,.00044,
.004946,.000729,
.004895,.001015,
.00483,.00129,
.00398,.00044,
180.*
4,1,15,.00044,-.00398,
.000208,-.003999,
-.000025,-.004004,
-.000258,-.003996,
-.00044,-.00398,
-.00129,-.00483,
-.001007,-.004897,
-.000721,-.004947,
-.000432,-.004981,
-.000141,-.004997,
.000149,-.004997,
.00044,-.00498,
.000729,-.004946,
.001015,-.004895,
.00129,-.00483,
.00044,-.00398,
180.*
4,1,15,-.00398,-.00044,
-.003999,-.000208,
-.004004,.000025,
-.003996,.000258,
-.00398,.00044,
-.00483,.00129,
-.004897,.001007,
-.004947,.000721,
-.004981,.000432,
-.004997,.000141,
-.004997,-.000149,
-.00498,-.00044,
-.004946,-.000729,
-.004895,-.001015,
-.00483,-.00129,
-.00398,-.00044,
180.*
4,1,15,-.00044,.00398,
-.000208,.003999,
.000025,.004004,
.000258,.003996,
.00044,.00398,
.00129,.00483,
.001007,.004897,
.000721,.004947,
.000432,.004981,
.000141,.004997,
-.000149,.004997,
-.00044,.00498,
-.000729,.004946,
-.001015,.004895,
-.00129,.00483,
-.00044,.00398,
180.*
%
%ADD13MACRO13*%
%AMMACRO26*
4,1,15,-.00398,.00044,
-.003999,.000208,
-.004004,-.000025,
-.003996,-.000258,
-.00398,-.00044,
-.00483,-.00129,
-.004897,-.001007,
-.004947,-.000721,
-.004981,-.000432,
-.004997,-.000141,
-.004997,.000149,
-.00498,.00044,
-.004946,.000729,
-.004895,.001015,
-.00483,.00129,
-.00398,.00044,
270.*
4,1,15,-.00044,-.00398,
-.000208,-.003999,
.000025,-.004004,
.000258,-.003996,
.00044,-.00398,
.00129,-.00483,
.001007,-.004897,
.000721,-.004947,
.000432,-.004981,
.000141,-.004997,
-.000149,-.004997,
-.00044,-.00498,
-.000729,-.004946,
-.001015,-.004895,
-.00129,-.00483,
-.00044,-.00398,
270.*
4,1,15,.00398,-.00044,
.003999,-.000208,
.004004,.000025,
.003996,.000258,
.00398,.00044,
.00483,.00129,
.004897,.001007,
.004947,.000721,
.004981,.000432,
.004997,.000141,
.004997,-.000149,
.00498,-.00044,
.004946,-.000729,
.004895,-.001015,
.00483,-.00129,
.00398,-.00044,
270.*
4,1,15,.00044,.00398,
.000208,.003999,
-.000025,.004004,
-.000258,.003996,
-.00044,.00398,
-.00129,.00483,
-.001007,.004897,
-.000721,.004947,
-.000432,.004981,
-.000141,.004997,
.000149,.004997,
.00044,.00498,
.000729,.004946,
.001015,.004895,
.00129,.00483,
.00044,.00398,
270.*
%
%ADD26MACRO26*%
%AMMACRO25*
4,1,15,-.00398,.00044,
-.003999,.000208,
-.004004,-.000025,
-.003996,-.000258,
-.00398,-.00044,
-.00483,-.00129,
-.004897,-.001007,
-.004947,-.000721,
-.004981,-.000432,
-.004997,-.000141,
-.004997,.000149,
-.00498,.00044,
-.004946,.000729,
-.004895,.001015,
-.00483,.00129,
-.00398,.00044,
180.*
4,1,15,-.00044,-.00398,
-.000208,-.003999,
.000025,-.004004,
.000258,-.003996,
.00044,-.00398,
.00129,-.00483,
.001007,-.004897,
.000721,-.004947,
.000432,-.004981,
.000141,-.004997,
-.000149,-.004997,
-.00044,-.00498,
-.000729,-.004946,
-.001015,-.004895,
-.00129,-.00483,
-.00044,-.00398,
180.*
4,1,15,.00398,-.00044,
.003999,-.000208,
.004004,.000025,
.003996,.000258,
.00398,.00044,
.00483,.00129,
.004897,.001007,
.004947,.000721,
.004981,.000432,
.004997,.000141,
.004997,-.000149,
.00498,-.00044,
.004946,-.000729,
.004895,-.001015,
.00483,-.00129,
.00398,-.00044,
180.*
4,1,15,.00044,.00398,
.000208,.003999,
-.000025,.004004,
-.000258,.003996,
-.00044,.00398,
-.00129,.00483,
-.001007,.004897,
-.000721,.004947,
-.000432,.004981,
-.000141,.004997,
.000149,.004997,
.00044,.00498,
.000729,.004946,
.001015,.004895,
.00129,.00483,
.00044,.00398,
180.*
%
%ADD25MACRO25*%
%ADD38C,.02*%
%ADD39C,.006*%
%ADD53O,.10334X.04822*%
%ADD42C,.06104*%
%ADD54C,.0824*%
%ADD41C,.07704*%
%ADD48O,.515X.315*%
%ADD40C,.11004*%
%ADD45C,.14304*%
%ADD43C,.13504*%
%ADD44C,.37504*%
%ADD46C,.29533*%
%ADD49O,.55202X.78802*%
%ADD50O,.09834X.04322*%
%ADD47O,.55204X.78804*%
%ADD52O,.09854X.04342*%
%ADD51O,.09836X.04324*%
G75*
%LPD*%
G75*
G36*
G01X-6000Y-6000D02*
X1940843D01*
Y1525685D01*
X-6000D01*
Y-6000D01*
G37*
%LPC*%
G75*
G36*
G01X1062059Y244094D02*
G03X1055118Y251035I-6941J0D01*
G01X818897D01*
G03X811957Y244095I1J-6941D01*
G01Y193701D01*
G02X811024Y192768I-933J0D01*
G01X787402D01*
G03X780461Y185827I0J-6941D01*
G01Y3937D01*
G02X779528Y3004I-933J0D01*
G01X3937D01*
G02X3004Y3937I0J933D01*
G01Y1456693D01*
G02X3937Y1457626I933J0D01*
G01X7874D01*
G03X14815Y1464567I0J6941D01*
G01Y1515748D01*
G02X15748Y1516681I933J0D01*
G01X60039D01*
G02X60972Y1515748I0J-933D01*
G01Y1509055D01*
G03X67913Y1502114I6941J0D01*
G01X93504D01*
G03X100445Y1509055I0J6941D01*
G01Y1515748D01*
G02X101378Y1516681I933J0D01*
G01X280709D01*
G02X281642Y1515748I0J-933D01*
G01Y1500000D01*
G03X288583Y1493059I6941J0D01*
G01X493307D01*
G03X500248Y1500000I0J6941D01*
G01Y1515748D01*
G02X501181Y1516681I933J0D01*
G01X680512D01*
G02X681445Y1515748I0J-933D01*
G01Y1509055D01*
G03X688386Y1502114I6941J0D01*
G01X713976D01*
G03X720917Y1509055I0J6941D01*
G01Y1515748D01*
G02X721850Y1516681I933J0D01*
G01X775591D01*
G02X776524Y1515748I0J-933D01*
G01Y1500000D01*
G03X783465Y1493059I6941J0D01*
G01X988189D01*
G03X995130Y1500000I0J6941D01*
G01Y1515748D01*
G02X996063Y1516681I933J0D01*
G01X1059198D01*
G02X1059856Y1516408I-1J-933D01*
G01X1069361Y1506903D01*
G02X1069634Y1506245I-660J-660D01*
G01Y1421260D01*
G03X1076575Y1414319I6941J0D01*
G01X1085630D01*
G03X1092571Y1421260I0J6941D01*
G01Y1506245D01*
G02X1092844Y1506903I933J-1D01*
G01X1102349Y1516408D01*
G02X1103007Y1516681I659J-660D01*
G01X1207283D01*
G02X1208216Y1515748I0J-933D01*
G01Y1509055D01*
G03X1215157Y1502114I6941J0D01*
G01X1240748D01*
G03X1247689Y1509055I0J6941D01*
G01Y1515748D01*
G02X1248622Y1516681I933J0D01*
G01X1427953D01*
G02X1428886Y1515748I0J-933D01*
G01Y1500000D01*
G03X1435827Y1493059I6941J0D01*
G01X1640551D01*
G03X1647492Y1500000I0J6941D01*
G01Y1515748D01*
G02X1648425Y1516681I933J0D01*
G01X1827756D01*
G02X1828689Y1515748I0J-933D01*
G01Y1509055D01*
G03X1835630Y1502114I6941J0D01*
G01X1861220D01*
G03X1868161Y1509055I0J6941D01*
G01Y1515748D01*
G02X1869094Y1516681I933J0D01*
G01X1919094D01*
G02X1920027Y1515748I0J-933D01*
G01Y1464567D01*
G03X1926967Y1457626I6941J0D01*
G01X1930906D01*
G02X1931839Y1456693I0J-933D01*
G01Y3937D01*
G02X1930906Y3004I-933J0D01*
G01X1228346D01*
G02X1227413Y3937I0J933D01*
G01Y185827D01*
G03X1220472Y192768I-6941J0D01*
G01X1062992D01*
G02X1062059Y193701I0J933D01*
G01Y244094D01*
G37*
%LPD*%
G75*
G36*
G01X1729038Y262991D02*
G02I-55121J0D01*
G37*
G36*
G01X558368Y715747D02*
G02I-55121J0D01*
G37*
G36*
G01X1575626Y103397D02*
G02X1608421Y103767I16499J-8808D01*
G02X1575626Y103397I-16295J-9279D01*
G37*
G36*
G01X129900Y76319D02*
Y71318D01*
G02X126076Y71319I-1912J1D01*
G01Y76319D01*
G02X129900I1912J0D01*
G37*
G36*
G01X136894Y61269D02*
Y56768D01*
G02X133072Y56769I-1911J1D01*
G01Y61269D01*
G02X136894I1911J0D01*
G37*
G36*
G01X126076Y524075D02*
Y529076D01*
G02X129900Y529075I1912J-1D01*
G01Y524075D01*
G02X126076I-1912J0D01*
G37*
G36*
G01X136894Y514025D02*
Y509524D01*
G02X133072Y509525I-1911J1D01*
G01Y514025D01*
G02X136894I1911J0D01*
G37*
G36*
G01X129900Y981831D02*
Y976830D01*
G02X126076Y976831I-1912J1D01*
G01Y981831D01*
G02X129900I1912J0D01*
G37*
G36*
G01X133072Y962281D02*
Y966782D01*
G02X136894Y966781I1911J-1D01*
G01Y962281D01*
G02X133072I-1911J0D01*
G37*
G36*
G01X254112Y76319D02*
Y71318D01*
G02X250288Y71319I-1912J1D01*
G01Y76319D01*
G02X254112I1912J0D01*
G37*
G36*
G01X261106Y61269D02*
Y56768D01*
G02X257284Y56769I-1911J1D01*
G01Y61269D01*
G02X261106I1911J0D01*
G37*
G36*
G01X250288Y524075D02*
Y529076D01*
G02X254112Y529075I1912J-1D01*
G01Y524075D01*
G02X250288I-1912J0D01*
G37*
G36*
G01X261106Y514025D02*
Y509524D01*
G02X257284Y509525I-1911J1D01*
G01Y514025D01*
G02X261106I1911J0D01*
G37*
G36*
G01X257284Y962281D02*
Y966782D01*
G02X261106Y966781I1911J-1D01*
G01Y962281D01*
G02X257284I-1911J0D01*
G37*
G36*
G01X254112Y981831D02*
Y976830D01*
G02X250288Y976831I-1912J1D01*
G01Y981831D01*
G02X254112I1912J0D01*
G37*
G36*
G01X385320Y61269D02*
Y56768D01*
G02X381496Y56769I-1912J1D01*
G01Y61269D01*
G02X385320I1912J0D01*
G37*
G36*
G01X378324Y76319D02*
Y71318D01*
G02X374502Y71319I-1911J1D01*
G01Y76319D01*
G02X378324I1911J0D01*
G37*
G36*
G01X374502Y524075D02*
Y529076D01*
G02X378324Y529075I1911J-1D01*
G01Y524075D01*
G02X374502I-1911J0D01*
G37*
G36*
G01X385320Y514025D02*
Y509524D01*
G02X381496Y509525I-1912J1D01*
G01Y514025D01*
G02X385320I1912J0D01*
G37*
G36*
G01X378324Y981831D02*
Y976830D01*
G02X374502Y976831I-1911J1D01*
G01Y981831D01*
G02X378324I1911J0D01*
G37*
G36*
G01X381496Y962281D02*
Y966782D01*
G02X385320Y966781I1912J-1D01*
G01Y962281D01*
G02X381496I-1912J0D01*
G37*
G36*
G01X636252Y1414252D02*
Y1291748D01*
X623752D01*
Y1287154D01*
X620846Y1284248D01*
X598154D01*
X593748Y1288654D01*
Y1300722D01*
X408680D01*
X401248Y1308154D01*
Y1364346D01*
X404748Y1367846D01*
Y1435479D01*
X408276Y1439006D01*
X431624D01*
X443109Y1427522D01*
X485893D01*
X499163Y1414252D01*
X636252D01*
G37*
G36*
G01X502536Y76319D02*
Y71318D01*
G02X498714Y71319I-1911J1D01*
G01Y76319D01*
G02X502536I1911J0D01*
G37*
G36*
G01X509532Y61269D02*
Y56768D01*
G02X505708Y56769I-1912J1D01*
G01Y61269D01*
G02X509532I1912J0D01*
G37*
G36*
G01X498714Y524075D02*
Y529076D01*
G02X502536Y529075I1911J-1D01*
G01Y524075D01*
G02X498714I-1911J0D01*
G37*
G36*
G01X509532Y514025D02*
Y509524D01*
G02X505708Y509525I-1912J1D01*
G01Y514025D01*
G02X509532I1912J0D01*
G37*
G36*
G01X502536Y981831D02*
Y976830D01*
G02X498714Y976831I-1911J1D01*
G01Y981831D01*
G02X502536I1911J0D01*
G37*
G36*
G01X505708Y962281D02*
Y966782D01*
G02X509532Y966781I1912J-1D01*
G01Y962281D01*
G02X505708I-1912J0D01*
G37*
G36*
G01X626750Y76319D02*
Y71318D01*
G02X622926Y71319I-1912J1D01*
G01Y76319D01*
G02X626750I1912J0D01*
G37*
G36*
G01X633744Y61269D02*
Y56768D01*
G02X629922Y56769I-1911J1D01*
G01Y61269D01*
G02X633744I1911J0D01*
G37*
G36*
G01X622926Y524075D02*
Y529076D01*
G02X626750Y529075I1912J-1D01*
G01Y524075D01*
G02X622926I-1912J0D01*
G37*
G36*
G01X633744Y514025D02*
Y509524D01*
G02X629922Y509525I-1911J1D01*
G01Y514025D01*
G02X633744I1911J0D01*
G37*
G36*
G01X622926Y976831D02*
Y981832D01*
G02X626750Y981831I1912J-1D01*
G01Y976831D01*
G02X622926I-1912J0D01*
G37*
G36*
G01X629922Y962281D02*
Y966782D01*
G02X633744Y966781I1911J-1D01*
G01Y962281D01*
G02X629922I-1911J0D01*
G37*
G36*
G01X651098Y1414252D02*
X805246D01*
X808902Y1410596D01*
Y1295254D01*
X805396Y1291748D01*
X651098D01*
Y1414252D01*
G37*
G36*
G01X757958Y61269D02*
Y56768D01*
G02X754134Y56769I-1912J1D01*
G01Y61269D01*
G02X757958I1912J0D01*
G37*
G36*
G01X750962Y76319D02*
Y71318D01*
G02X747140Y71319I-1911J1D01*
G01Y76319D01*
G02X750962I1911J0D01*
G37*
G36*
G01X757958Y514025D02*
Y509524D01*
G02X754134Y509525I-1912J1D01*
G01Y514025D01*
G02X757958I1912J0D01*
G37*
G36*
G01X750962Y529075D02*
Y524074D01*
G02X747140Y524075I-1911J1D01*
G01Y529075D01*
G02X750962I1911J0D01*
G37*
G36*
G01Y981831D02*
Y976830D01*
G02X747140Y976831I-1911J1D01*
G01Y981831D01*
G02X750962I1911J0D01*
G37*
G36*
G01X754134Y962281D02*
Y966782D01*
G02X757958Y966781I1912J-1D01*
G01Y962281D01*
G02X754134I-1912J0D01*
G37*
G36*
G01X824610Y277165D02*
Y282678D01*
G02X828934Y282677I2162J-1D01*
G01Y277165D01*
G02X824610I-2162J0D01*
G37*
G36*
G01X852956D02*
Y282678D01*
G02X857280Y282677I2162J-1D01*
G01Y277165D01*
G02X852956I-2162J0D01*
G37*
G36*
G01X838784D02*
Y282678D01*
G02X843106Y282677I2161J-1D01*
G01Y277165D01*
G02X838784I-2161J0D01*
G37*
G36*
G01X860044Y258268D02*
Y263780D01*
G02X864366Y263779I2161J-1D01*
G01Y258268D01*
G02X860044I-2161J0D01*
G37*
G36*
G01X845870D02*
Y263780D01*
G02X850194Y263779I2162J-1D01*
G01Y258268D01*
G02X845870I-2162J0D01*
G37*
G36*
G01X831698D02*
Y263780D01*
G02X836020Y263779I2161J-1D01*
G01Y258268D01*
G02X831698I-2161J0D01*
G37*
G36*
G01X860044Y300787D02*
Y306300D01*
G02X864366Y306299I2161J-1D01*
G01Y300787D01*
G02X860044I-2161J0D01*
G37*
G36*
G01X845870D02*
Y306300D01*
G02X850194Y306299I2162J-1D01*
G01Y300787D01*
G02X845870I-2162J0D01*
G37*
G36*
G01X857280Y311023D02*
Y305511D01*
G02X852956Y305512I-2162J1D01*
G01Y311023D01*
G02X857280I2162J0D01*
G37*
G36*
G01X843106D02*
Y305511D01*
G02X838784Y305512I-2161J1D01*
G01Y311023D01*
G02X843106I2161J0D01*
G37*
G36*
G01X831698Y300787D02*
Y306300D01*
G02X836020Y306299I2161J-1D01*
G01Y300787D01*
G02X831698I-2161J0D01*
G37*
G36*
G01X828934Y311023D02*
Y305511D01*
G02X824610Y305512I-2162J1D01*
G01Y311023D01*
G02X828934I2162J0D01*
G37*
G36*
G01X824610Y291338D02*
Y296851D01*
G02X828934Y296850I2162J-1D01*
G01Y291338D01*
G02X824610I-2162J0D01*
G37*
G36*
G01X867130Y277165D02*
Y282678D01*
G02X871454Y282677I2162J-1D01*
G01Y277165D01*
G02X867130I-2162J0D01*
G37*
G36*
G01X878540Y263779D02*
Y258267D01*
G02X874216Y258268I-2162J1D01*
G01Y263779D01*
G02X878540I2162J0D01*
G37*
G36*
G01X874216Y300787D02*
Y306300D01*
G02X878540Y306299I2162J-1D01*
G01Y300787D01*
G02X874216I-2162J0D01*
G37*
G36*
G01X871454Y311023D02*
Y305511D01*
G02X867130Y305512I-2162J1D01*
G01Y311023D01*
G02X871454I2162J0D01*
G37*
G36*
G01X1270400Y70562D02*
X1275401D01*
G02X1275400Y66738I-1J-1912D01*
G01X1270400D01*
G02Y70562I0J1912D01*
G37*
G36*
G01X1261250Y51738D02*
X1256749D01*
G02X1256750Y55562I1J1912D01*
G01X1261250D01*
G02Y51738I0J-1912D01*
G37*
G36*
G01Y504494D02*
X1256749D01*
G02X1256750Y508318I1J1912D01*
G01X1261250D01*
G02Y504494I0J-1912D01*
G37*
G36*
G01X1270400Y523318D02*
X1275401D01*
G02X1275400Y519494I-1J-1912D01*
G01X1270400D01*
G02Y523318I0J1912D01*
G37*
G36*
G01X1275886Y981831D02*
Y976830D01*
G02X1272064Y976831I-1911J1D01*
G01Y981831D01*
G02X1275886I1911J0D01*
G37*
G36*
G01X1255578Y961861D02*
Y966362D01*
G02X1259402Y966361I1912J-1D01*
G01Y961861D01*
G02X1255578I-1912J0D01*
G37*
G36*
G01X1399613Y66738D02*
X1394612D01*
G02X1394613Y70562I1J1912D01*
G01X1399613D01*
G02Y66738I0J-1912D01*
G37*
G36*
G01X1385463Y51738D02*
X1380962D01*
G02X1380963Y55562I1J1912D01*
G01X1385463D01*
G02Y51738I0J-1912D01*
G37*
G36*
G01X1399613Y519494D02*
X1394612D01*
G02X1394613Y523318I1J1912D01*
G01X1399613D01*
G02Y519494I0J-1912D01*
G37*
G36*
G01X1385463Y504494D02*
X1380962D01*
G02X1380963Y508318I1J1912D01*
G01X1385463D01*
G02Y504494I0J-1912D01*
G37*
G36*
G01X1400100Y981831D02*
Y976830D01*
G02X1396276Y976831I-1912J1D01*
G01Y981831D01*
G02X1400100I1912J0D01*
G37*
G36*
G01X1379752Y961881D02*
Y966382D01*
G02X1383574Y966381I1911J-1D01*
G01Y961881D01*
G02X1379752I-1911J0D01*
G37*
G36*
G01X1509675Y51738D02*
X1505174D01*
G02X1505175Y55562I1J1912D01*
G01X1509675D01*
G02Y51738I0J-1912D01*
G37*
G36*
G01X1518825Y70562D02*
X1523826D01*
G02X1523825Y66738I-1J-1912D01*
G01X1518825D01*
G02Y70562I0J1912D01*
G37*
G36*
G01Y523318D02*
X1523826D01*
G02X1523825Y519494I-1J-1912D01*
G01X1518825D01*
G02Y523318I0J1912D01*
G37*
G36*
G01X1509675Y504494D02*
X1505174D01*
G02X1505175Y508318I1J1912D01*
G01X1509675D01*
G02Y504494I0J-1912D01*
G37*
G36*
G01X1524312Y981831D02*
Y976830D01*
G02X1520488Y976831I-1912J1D01*
G01Y981831D01*
G02X1524312I1912J0D01*
G37*
G36*
G01X1503964Y961821D02*
Y966322D01*
G02X1507786Y966321I1911J-1D01*
G01Y961821D01*
G02X1503964I-1911J0D01*
G37*
G36*
G01X1648038Y66738D02*
X1643037D01*
G02X1643038Y70562I1J1912D01*
G01X1648038D01*
G02Y66738I0J-1912D01*
G37*
G36*
G01X1633888Y51738D02*
X1629387D01*
G02X1629388Y55562I1J1912D01*
G01X1633888D01*
G02Y51738I0J-1912D01*
G37*
G36*
G01X1648038Y519494D02*
X1643037D01*
G02X1643038Y523318I1J1912D01*
G01X1648038D01*
G02Y519494I0J-1912D01*
G37*
G36*
G01X1633888Y504494D02*
X1629387D01*
G02X1629388Y508318I1J1912D01*
G01X1633888D01*
G02Y504494I0J-1912D01*
G37*
G36*
G01X1648524Y981831D02*
Y976830D01*
G02X1644702Y976831I-1911J1D01*
G01Y981831D01*
G02X1648524I1911J0D01*
G37*
G36*
G01X1628176Y962381D02*
Y966882D01*
G02X1632000Y966881I1912J-1D01*
G01Y962381D01*
G02X1628176I-1912J0D01*
G37*
G36*
G01X1767250Y70562D02*
X1772251D01*
G02X1772250Y66738I-1J-1912D01*
G01X1767250D01*
G02Y70562I0J1912D01*
G37*
G36*
G01X1758100Y51738D02*
X1753599D01*
G02X1753600Y55562I1J1912D01*
G01X1758100D01*
G02Y51738I0J-1912D01*
G37*
G36*
G01X1767250Y523318D02*
X1772251D01*
G02X1772250Y519494I-1J-1912D01*
G01X1767250D01*
G02Y523318I0J1912D01*
G37*
G36*
G01X1758100Y504494D02*
X1753599D01*
G02X1753600Y508318I1J1912D01*
G01X1758100D01*
G02Y504494I0J-1912D01*
G37*
G36*
G01X1772736Y981831D02*
Y976830D01*
G02X1768914Y976831I-1911J1D01*
G01Y981831D01*
G02X1772736I1911J0D01*
G37*
G36*
G01X1752428Y961861D02*
Y966362D01*
G02X1756252Y966361I1912J-1D01*
G01Y961861D01*
G02X1752428I-1912J0D01*
G37*
G36*
G01X1896463Y66738D02*
X1891462D01*
G02X1891463Y70562I1J1912D01*
G01X1896463D01*
G02Y66738I0J-1912D01*
G37*
G36*
G01X1882313Y51738D02*
X1877812D01*
G02X1877813Y55562I1J1912D01*
G01X1882313D01*
G02Y51738I0J-1912D01*
G37*
G36*
G01X1896463Y519494D02*
X1891462D01*
G02X1891463Y523318I1J1912D01*
G01X1896463D01*
G02Y519494I0J-1912D01*
G37*
G36*
G01X1882313Y504494D02*
X1877812D01*
G02X1877813Y508318I1J1912D01*
G01X1882313D01*
G02Y504494I0J-1912D01*
G37*
G36*
G01X1896950Y981831D02*
Y976830D01*
G02X1893126Y976831I-1912J1D01*
G01Y981831D01*
G02X1896950I1912J0D01*
G37*
G36*
G01X1876642Y961861D02*
Y966362D01*
G02X1880464Y966361I1911J-1D01*
G01Y961861D01*
G02X1876642I-1911J0D01*
G37*
G54D53*
X1130459Y883049D03*
G54D42*
X1902756Y945020D03*
Y492264D03*
Y39508D03*
X1778543Y945020D03*
Y492264D03*
Y39508D03*
X1654331Y945020D03*
Y492264D03*
Y39508D03*
X1530118Y945020D03*
Y492264D03*
Y39508D03*
X1405906Y945020D03*
Y492264D03*
Y39508D03*
X1281693Y945020D03*
Y492264D03*
Y39508D03*
X732087Y945020D03*
Y492264D03*
Y39508D03*
X607874Y945020D03*
Y492264D03*
Y39508D03*
X483661Y945020D03*
Y492264D03*
Y39508D03*
X359449Y945020D03*
Y492264D03*
Y39508D03*
X235236Y945020D03*
Y492264D03*
Y39508D03*
X111024Y945020D03*
Y492264D03*
Y39508D03*
G54D54*
X80709Y1485118D03*
X701181D03*
X1227953D03*
X1848425D03*
G54D41*
X1902756Y1093642D03*
Y640886D03*
Y188130D03*
X1778543Y1093642D03*
Y640886D03*
Y188130D03*
X1654331Y1093642D03*
Y640886D03*
Y188130D03*
X1530118Y1093642D03*
Y640886D03*
Y188130D03*
X1405906Y1093642D03*
Y640886D03*
Y188130D03*
X1281693Y1093642D03*
Y640886D03*
Y188130D03*
X732087Y1093642D03*
Y640886D03*
Y188130D03*
X607874Y1093642D03*
Y640886D03*
Y188130D03*
X483661Y1093642D03*
Y640886D03*
Y188130D03*
X359449Y1093642D03*
Y640886D03*
Y188130D03*
X235236Y1093642D03*
Y640886D03*
Y188130D03*
X111024Y1093642D03*
Y640886D03*
Y188130D03*
G54D48*
X256535Y1320472D03*
G54D40*
X1869500Y1461500D03*
X63374Y1454500D03*
X59400Y32600D03*
G54D45*
X1761417Y1495669D03*
X1695275D03*
X1381102D03*
X1314960D03*
X614173D03*
X548031D03*
X233858D03*
X167716D03*
G54D43*
X1840551Y122046D03*
X1343701D03*
X670079Y122047D03*
X173228D03*
G54D44*
X1840551Y55118D03*
X1343701D03*
X670078D03*
X421653Y94488D03*
X173228Y55118D03*
G54D46*
X1104527Y1162258D03*
G54D49*
X627263Y262981D03*
Y715737D03*
Y1168492D03*
X961417Y703925D03*
Y972429D03*
X1181889Y381878D03*
Y972429D03*
X1549901Y262981D03*
Y715737D03*
Y1168492D03*
X1797933Y262980D03*
Y715737D03*
Y1168492D03*
G54D50*
X1098176Y520057D03*
Y548403D03*
X1102113Y527143D03*
Y569663D03*
X1126522Y548403D03*
X1130459Y541317D03*
Y527143D03*
X1126522Y520057D03*
X1116286Y569663D03*
X1130459D03*
X1098176Y691711D03*
X1102113Y698797D03*
Y741317D03*
X1098176Y748403D03*
Y720057D03*
Y762577D03*
X1126522Y691711D03*
X1130459Y698797D03*
Y741317D03*
X1126522Y748403D03*
Y720057D03*
Y762577D03*
X1102113Y769663D03*
X1098176Y790923D03*
Y833443D03*
X1102113Y840529D03*
Y854703D03*
Y812183D03*
X1130459Y769663D03*
X1126522Y790923D03*
Y833443D03*
X1130459Y840529D03*
Y854703D03*
Y812183D03*
X1098176Y904309D03*
Y861789D03*
X1102113Y883049D03*
Y925569D03*
X1098176Y932655D03*
X1126522Y904309D03*
Y861789D03*
X1130459Y925569D03*
X1126522Y932655D03*
G54D47*
X131200Y262981D03*
Y715737D03*
Y1168492D03*
X379232Y262981D03*
Y715737D03*
Y1168492D03*
X747244Y381878D03*
Y814949D03*
X1301870Y262980D03*
Y715737D03*
Y1168492D03*
G54D52*
X1102113Y541317D03*
G54D51*
X1098176Y562576D03*
X1102113Y555490D03*
X1098176Y534230D03*
X1126522Y562576D03*
X1130459Y555490D03*
X1126522Y534230D03*
X1098176Y705884D03*
Y734230D03*
X1102113Y755490D03*
Y712970D03*
Y727144D03*
X1126522Y705884D03*
Y734230D03*
X1130459Y755490D03*
Y712970D03*
Y727144D03*
X1098176Y805096D03*
X1102113Y798010D03*
Y783836D03*
X1098176Y776750D03*
Y819270D03*
X1102113Y826356D03*
X1098176Y847616D03*
X1126522Y776750D03*
X1130459Y783836D03*
Y798010D03*
X1126522Y805096D03*
Y819270D03*
X1130459Y826356D03*
X1126522Y847616D03*
X1102113Y868876D03*
Y897222D03*
X1098176Y890136D03*
Y875962D03*
X1102113Y911396D03*
X1098176Y918482D03*
X1102113Y939742D03*
X1130459Y868876D03*
X1126522Y875962D03*
X1130459Y897222D03*
X1126522Y890136D03*
X1130459Y911396D03*
X1126522Y918482D03*
X1130459Y939742D03*
%LPC*%
G75*
G36*
G01X599811Y1288250D02*
X597750Y1290311D01*
Y1302811D01*
X595837Y1304724D01*
X536520D01*
G02X536396Y1305504I0J400D01*
G03X531496Y1336222I-4900J14968D01*
G01X511496D01*
G03X506596Y1305504I0J-15750D01*
G02X506472Y1304724I-124J-380D01*
G01X410337D01*
X405250Y1309811D01*
Y1362689D01*
X408750Y1366189D01*
Y1433822D01*
X409933Y1435005D01*
X429967D01*
X441452Y1423520D01*
X484236D01*
X497506Y1410250D01*
X632250D01*
Y1295750D01*
X621689D01*
X619750Y1293811D01*
Y1288811D01*
X619189Y1288250D01*
X599811D01*
G37*
G36*
G01X803739Y1295750D02*
X655100D01*
Y1410250D01*
X803589D01*
X804900Y1408939D01*
Y1296911D01*
X803739Y1295750D01*
G37*
%LPD*%
G75*
G54D35*
X834000Y1324500D03*
Y1317500D03*
Y1310500D03*
Y1303500D03*
X827000D03*
X820000D03*
X827000Y1310500D03*
X820000D03*
X827000Y1317500D03*
X820000D03*
X827000Y1324500D03*
X820000D03*
X834000Y1386000D03*
Y1379000D03*
Y1363000D03*
Y1356000D03*
Y1349000D03*
Y1342000D03*
X827000D03*
X820000D03*
X827000Y1349000D03*
X820000D03*
X827000Y1356000D03*
X820000D03*
X827000Y1363000D03*
X820000D03*
X827000Y1379000D03*
X820000D03*
X827000Y1386000D03*
X820000D03*
X827000Y1393000D03*
X820000D03*
X958200Y1303900D03*
X942400D03*
X950300D03*
X934500D03*
X926600D03*
X958200Y1311800D03*
X926600D03*
X934500D03*
X950300D03*
X942400D03*
X903500Y1319400D03*
X950300Y1319700D03*
X958200D03*
X934500D03*
X942400D03*
X926600D03*
X918700D03*
X910800D03*
X887800Y1327100D03*
X934700Y1327500D03*
X895200D03*
X903100D03*
X911000D03*
X926800D03*
X918900D03*
X887800Y1335000D03*
X886400Y1368100D03*
Y1376000D03*
X894300D03*
Y1368100D03*
X934700Y1335400D03*
X926800D03*
X918900D03*
X895200D03*
X903100D03*
X911000D03*
X890400Y1358900D03*
X887800Y1350800D03*
Y1342900D03*
X937300Y1359300D03*
X934700Y1343300D03*
Y1351200D03*
X926800Y1343300D03*
Y1351200D03*
X929400Y1359300D03*
X918900Y1343300D03*
Y1351200D03*
X921500Y1359300D03*
X918000Y1368100D03*
Y1376000D03*
X910100Y1368100D03*
Y1376000D03*
X911000Y1343300D03*
Y1351200D03*
X913600Y1359300D03*
X903100Y1343300D03*
Y1351200D03*
X905700Y1359300D03*
X902200Y1376000D03*
Y1368100D03*
X897800Y1359300D03*
X895200Y1351200D03*
Y1343300D03*
X998600Y1300900D03*
X991500Y1312100D03*
X1020800Y1300400D03*
X991455Y1320416D03*
X996400Y1315900D03*
X996200Y1307800D03*
X1014000Y1300600D03*
X991755Y1327716D03*
X996055Y1324116D03*
X1007100Y1301100D03*
X1011100Y1305300D03*
X1019829Y1306139D03*
X1002700Y1305700D03*
X991800Y1303400D03*
X1000200Y1311700D03*
Y1320500D03*
X1016429Y1333939D03*
X1021829D03*
X1011029D03*
X1005629D03*
X986755Y1323816D03*
X986700Y1307600D03*
X1000200Y1328100D03*
X1050818Y1311189D03*
Y1316589D03*
X1045418Y1321989D03*
X1050818D03*
X1034618Y1311189D03*
X1040018D03*
X1045418D03*
X1040018Y1316589D03*
X1034618D03*
X1040018Y1321989D03*
X1031600Y1335100D03*
X1037200Y1335000D03*
X1034618Y1321989D03*
X997900Y1335800D03*
X992500D03*
X997900Y1341200D03*
X992500D03*
X997900Y1346600D03*
X992500D03*
X997900Y1352000D03*
X992500D03*
Y1357400D03*
X997900D03*
X989083Y1387764D03*
X989509Y1393422D03*
X994700Y1385000D03*
X999700Y1374500D03*
X989100Y1381700D03*
X994200Y1362700D03*
X1019829Y1389539D03*
X1013692Y1389688D03*
X1019829Y1361739D03*
X1014306Y1361710D03*
X1008870Y1361681D03*
X1003367Y1361655D03*
X1004217Y1389394D03*
X1008298Y1393071D03*
X994400Y1377300D03*
X999930Y1393070D03*
X999800Y1381600D03*
X999900Y1366800D03*
X994300Y1370100D03*
X989200Y1374800D03*
X988900Y1366900D03*
X1034600Y1349600D03*
X1042400Y1349500D03*
X1037540Y1344964D03*
X1034799Y1340183D03*
X1044700Y1335500D03*
X1043300Y1342500D03*
X1048000Y1346100D03*
X1037111Y1372380D03*
X1039988Y1367352D03*
X1044400Y1363100D03*
X1036900Y1362600D03*
X1034380Y1367469D03*
X1031300Y1362700D03*
X1042100Y1377100D03*
X1034300Y1377200D03*
X1047401Y1375084D03*
X1066481Y1327759D03*
X1061081D03*
X1066481Y1333159D03*
X1061081D03*
X1061618Y1316589D03*
X1056218Y1311189D03*
X1061618D03*
X1056218Y1316589D03*
X1060218Y1321989D03*
X1066491Y1319983D03*
X1066407Y1313972D03*
X1066481Y1338559D03*
X1061081D03*
X1066481Y1343959D03*
X1061081D03*
X1066481Y1376359D03*
Y1349359D03*
Y1354759D03*
Y1360159D03*
Y1365559D03*
Y1370959D03*
X1061081Y1376359D03*
Y1370959D03*
Y1365559D03*
Y1360159D03*
Y1354759D03*
Y1349359D03*
G54D12*
X92500Y62800D03*
X56750Y62000D03*
X64250Y87500D03*
X95800Y71800D03*
X30500Y67000D03*
X74000Y87500D03*
X89000D03*
X84000D03*
X79000D03*
X50000Y105500D03*
X54500D03*
X59000D03*
X58709Y372346D03*
X84581Y397946D03*
X79581D03*
X93800Y516800D03*
X64250Y540000D03*
X50000Y558000D03*
X54500D03*
X59000D03*
X53250Y518000D03*
X95500Y525500D03*
X79000Y540000D03*
X84000D03*
X89000D03*
X74000D03*
X46442Y825000D03*
X73526Y850100D03*
X68526D03*
X83300Y908900D03*
X100310Y899557D03*
X68900Y897700D03*
X77263Y898225D03*
X83500Y898662D03*
X73430Y898509D03*
X70603Y887495D03*
X66263Y879525D03*
X67763Y883525D03*
X95500Y968000D03*
X59000Y1011000D03*
X54500D03*
X50000D03*
X64250Y993000D03*
X53250Y971000D03*
X95500Y972500D03*
X74000Y993000D03*
X89000D03*
X84000D03*
X79000D03*
X183500Y75450D03*
Y80250D03*
X178500Y80000D03*
X185551Y21529D03*
X151200Y48500D03*
Y44400D03*
X145864Y33216D03*
X175650Y28600D03*
X131600Y119100D03*
X192842Y372000D03*
X181127Y471164D03*
X166727Y459964D03*
X175090Y460489D03*
X181327Y460926D03*
X171257Y460773D03*
X168430Y449759D03*
X165590Y445789D03*
X164127Y442264D03*
X188250Y540000D03*
X176439Y524992D03*
X182300Y558600D03*
X173600Y554400D03*
Y558600D03*
X178100D03*
X176506Y539295D03*
X143000Y587000D03*
X169442Y824700D03*
X191026Y850100D03*
X196026D03*
X102263Y919025D03*
X114563Y904041D03*
X113763Y865025D03*
X106263Y900025D03*
X106363Y893425D03*
X102207Y890524D03*
X183500Y1011000D03*
X179000D03*
X174500D03*
X188750Y993000D03*
X178200Y977700D03*
X140750Y1039250D03*
X125500Y992500D03*
X130601Y1411700D03*
X136774Y1411000D03*
X188274Y1416600D03*
X165774Y1422700D03*
X124874Y1442600D03*
X151874Y1449800D03*
X149955Y1431573D03*
X135374Y1464000D03*
Y1445500D03*
X105774Y1491000D03*
X120474Y1482800D03*
X132674Y1484200D03*
X137624Y1469000D03*
X175249Y1434075D03*
X156374Y1430500D03*
X130322Y1434014D03*
X135174Y1452400D03*
X104184Y1457200D03*
X139374Y1486100D03*
X124074Y1437200D03*
X113314Y1441700D03*
X220000Y80500D03*
X200819Y74819D03*
X217000Y38250D03*
X198800Y34000D03*
X203078Y33972D03*
X215500Y80500D03*
X203000Y87500D03*
X213000D03*
X208000D03*
X197500D03*
X254900Y119600D03*
X218214Y397600D03*
X213214D03*
X212390Y466305D03*
X198137Y461821D03*
X204090Y462289D03*
X204190Y455689D03*
X200022Y452941D03*
X218000Y516600D03*
X200090Y481289D03*
X220000Y524000D03*
X203000Y540000D03*
X208000D03*
X213000D03*
X198000D03*
X264750Y586250D03*
X197263Y901025D03*
X218100Y969700D03*
X264450Y1039250D03*
X252000Y992500D03*
X220000Y978200D03*
X198500Y993000D03*
X213500D03*
X208500D03*
X203500D03*
X209374Y1416300D03*
X341800Y63700D03*
X311800Y83700D03*
X301750Y65500D03*
X340650Y69300D03*
X327500Y87500D03*
X332500D03*
X337500D03*
X322500D03*
X293700Y105500D03*
X298500D03*
X302999Y105501D03*
X379500Y119500D03*
X294542Y372300D03*
X320514Y397600D03*
X315514D03*
X295090Y463289D03*
X341800Y516800D03*
X312750Y536300D03*
X299104Y556943D03*
X303604D03*
X308104D03*
X301750Y518000D03*
X344000Y525300D03*
X322500Y540000D03*
X337500D03*
X332500D03*
X327500D03*
X294542Y825000D03*
X320526Y850100D03*
X315526D03*
X341900Y969400D03*
X307500Y1011000D03*
X303000D03*
X298500D03*
X312750Y993000D03*
X302100Y978200D03*
X376000Y993000D03*
X344200Y978200D03*
X322500Y993000D03*
X337500D03*
X332500D03*
X327500D03*
X425500Y72600D03*
X435500D03*
X430500D03*
X440500D03*
X468500Y80500D03*
X465500Y38250D03*
X425500Y41250D03*
X430500D03*
X434804Y41242D03*
X444663Y32417D03*
X440400Y32400D03*
X464000Y80500D03*
X446400Y91100D03*
X456900D03*
X461900D03*
X451900D03*
X437500Y134500D03*
X441500D03*
X433500D03*
X430083Y122357D03*
X419042Y372000D03*
X445014Y397600D03*
X440014D03*
X466000Y516900D03*
X436750Y538400D03*
X422500Y558000D03*
X427000D03*
X431500D03*
X429210Y512992D03*
X464801Y521156D03*
X446500Y540000D03*
X461500D03*
X456500D03*
X451500D03*
X390632Y588624D03*
X418742Y824444D03*
X440026Y850100D03*
X445026D03*
X466100Y969200D03*
X431500Y1011000D03*
X427000D03*
X422500D03*
X436750Y993000D03*
X426300Y976800D03*
X389250Y1039250D03*
X468300Y978000D03*
X446500Y993000D03*
X461500D03*
X456500D03*
X451500D03*
X561250Y87500D03*
X550250Y65500D03*
X576000Y87500D03*
X571000D03*
X547000Y105500D03*
X551500D03*
X556000D03*
X503900Y119500D03*
X543242Y372300D03*
X569014Y397600D03*
X564014D03*
X561250Y540000D03*
X550250Y518000D03*
X571000Y540000D03*
X576000D03*
X516000Y637413D03*
X546500Y572000D03*
X551044Y572149D03*
X555321Y572375D03*
X517999Y583015D03*
X564026Y850100D03*
X569026D03*
X556000Y1011000D03*
X551500D03*
X547000D03*
X561250Y993000D03*
X550700Y979500D03*
X513250Y1039250D03*
X500000Y992000D03*
X571000Y993000D03*
X576000D03*
X523455Y1416564D03*
X535200Y1466100D03*
X523500Y1455400D03*
X503001Y1454922D03*
X513624Y1458624D03*
X504000Y1470500D03*
X503035Y1444331D03*
X528250Y1470900D03*
X496500Y1476000D03*
X508867Y1497771D03*
X590600Y64300D03*
X670500Y80000D03*
X589150Y69500D03*
X581000Y87500D03*
X586000D03*
X628000Y119500D03*
X654242Y372000D03*
X583550Y504600D03*
X672018Y557014D03*
X592500Y525300D03*
X586000Y540000D03*
X581000D03*
X664651Y513000D03*
X666900Y665400D03*
X637750Y586250D03*
X646680Y679430D03*
X582648Y825223D03*
X659642Y824700D03*
X585904Y900960D03*
X589904D03*
X593904D03*
X597904D03*
X601904D03*
X673000Y885500D03*
X590200Y969500D03*
X671000Y1011000D03*
X624500Y993000D03*
X592800Y978100D03*
X586000Y993000D03*
X581000D03*
X646102Y1321750D03*
X641102D03*
X668000Y1418900D03*
X672000Y1419000D03*
X646200Y1420576D03*
X641200D03*
X637971Y1425400D03*
X657836Y1433318D03*
X658000Y1449200D03*
X665700Y1463500D03*
Y1468500D03*
X650000Y1464052D03*
Y1467948D03*
Y1457448D03*
Y1453552D03*
X636250Y1468500D03*
X628500D03*
X637972Y1441419D03*
X658000Y1444000D03*
X665700Y1458000D03*
Y1453000D03*
X624750Y1461250D03*
X712214Y82500D03*
X680500Y80250D03*
X675500Y80000D03*
X697787Y74488D03*
X714000Y38250D03*
X695600Y34000D03*
X699932Y34034D03*
X709000Y79500D03*
X700000Y87500D03*
X705000D03*
X710000D03*
X694500D03*
X711352Y26875D03*
X715205Y27012D03*
X705171Y16254D03*
X753473Y138459D03*
X685514Y397600D03*
X680514D03*
X698600Y511100D03*
X685250Y540000D03*
X680902Y557860D03*
X676402D03*
X674250Y518000D03*
X714600Y498100D03*
X716400Y525200D03*
X695000Y540000D03*
X700000D03*
X705000D03*
X710000D03*
X752200Y572300D03*
X709871Y686246D03*
X718100Y738500D03*
X718200Y744000D03*
X723000Y739200D03*
X723300Y743700D03*
X728175Y741300D03*
X728100Y745500D03*
X680526Y850100D03*
X685526D03*
X701700Y872700D03*
X714500Y870100D03*
X723600Y872400D03*
X712760Y915137D03*
X727600Y872300D03*
X733895Y901054D03*
X754000Y884524D03*
X757600Y884400D03*
X677000Y885500D03*
X714400Y969600D03*
X680000Y1011000D03*
X675500D03*
X685250Y993000D03*
X675400Y980500D03*
X755200Y992400D03*
X716800Y978300D03*
X700000Y993000D03*
X705000D03*
X710000D03*
X695000D03*
X759249Y1008800D03*
X759700Y1138600D03*
X759762Y1135000D03*
X698500Y1418900D03*
X693000Y1418800D03*
X689000Y1419000D03*
X681000Y1419100D03*
X685000Y1418900D03*
X703500Y1426000D03*
X676500Y1419500D03*
X742880Y1422632D03*
X739532Y1425934D03*
X720455Y1438500D03*
X684000Y1482000D03*
X699500Y1476000D03*
X685000Y1453500D03*
X690000Y1448500D03*
X695000Y1453500D03*
X690000Y1458500D03*
Y1453500D03*
X680900Y1469200D03*
X680200Y1465500D03*
X675550Y1458721D03*
Y1452216D03*
X692000Y1471156D03*
X689250Y1433500D03*
X681250D03*
X745000Y1463000D03*
X730341Y1446725D03*
X756332Y1465934D03*
X745032Y1468534D03*
X732232Y1477094D03*
X718900Y1472800D03*
X679800Y1483500D03*
X708600Y1469900D03*
X724066Y1461018D03*
X724255Y1457253D03*
X735232Y1451210D03*
X835165Y470414D03*
X787971Y466121D03*
X791971D03*
X787971Y461921D03*
X791971D03*
X787971Y457721D03*
X791971D03*
X848799Y457202D03*
X849539Y453596D03*
X827313Y464805D03*
X827361Y459317D03*
X860519Y428234D03*
X860716Y417600D03*
X850947Y417592D03*
X832417Y459017D03*
X812282Y448094D03*
X815255Y451343D03*
X808395Y454315D03*
X858740Y486430D03*
X794883Y639984D03*
X798475Y640227D03*
X863430Y618590D03*
X788160Y666220D03*
X814320Y651120D03*
X813980Y647430D03*
X860360Y605900D03*
X836862Y637500D03*
X815148Y654937D03*
X824618Y614617D03*
X827750Y611798D03*
X791530Y614700D03*
X791680Y619050D03*
X799900Y636300D03*
X807440Y629910D03*
X802900Y634000D03*
X837709Y681095D03*
X789442Y681063D03*
X796200Y682400D03*
X791243Y668081D03*
X778627Y735644D03*
X778683Y745049D03*
X778735Y839888D03*
X791500Y764500D03*
X795300Y764900D03*
X826000Y857400D03*
X815469Y811029D03*
X815330Y807050D03*
X818113Y814998D03*
X834200Y796220D03*
X810700Y772000D03*
Y781000D03*
X858500Y845700D03*
X858100Y850000D03*
X848300Y847700D03*
X804200Y798200D03*
X811372Y795900D03*
X808372Y797900D03*
X805372Y801700D03*
X825900Y862040D03*
X801300Y924300D03*
X799303Y927296D03*
X822463Y920345D03*
X842270Y936402D03*
X861300Y895300D03*
X819000Y896100D03*
X817337Y886075D03*
X815400Y892800D03*
X844800Y895902D03*
X845732Y891713D03*
X839970Y981470D03*
X834470D03*
X826470D03*
X848400Y974100D03*
X836953Y1023500D03*
X842700Y1071900D03*
X782712Y1211404D03*
Y1206904D03*
X772601Y1223511D03*
Y1219011D03*
Y1214511D03*
X777101Y1223511D03*
X832800Y1147500D03*
X795100Y1150400D03*
X798920Y1150500D03*
X821900Y1173700D03*
X773300Y1159700D03*
X769800Y1156500D03*
X776800Y1169700D03*
X780722Y1166357D03*
X780000Y1162800D03*
X822500Y1331000D03*
Y1298000D03*
Y1294000D03*
X852000Y1402000D03*
Y1406000D03*
X822500Y1373500D03*
Y1369500D03*
X835000Y1402500D03*
Y1398000D03*
X822500Y1335000D03*
X772361Y1451972D03*
X882823Y331182D03*
X909236Y333242D03*
X906486Y330524D03*
X910330Y363490D03*
X908340Y360430D03*
X909423Y354393D03*
X898059Y343029D03*
X902184Y347219D03*
X906616Y351586D03*
X922800Y362400D03*
X922700Y358100D03*
X945408Y378761D03*
X950843Y378827D03*
X871591Y431161D03*
X870400Y454315D03*
X867299Y493300D03*
Y497200D03*
X922525Y519833D03*
X873000Y494100D03*
X929096Y517567D03*
X873200Y487300D03*
X944387Y520100D03*
X941557Y547005D03*
X955000Y540800D03*
X935477Y524023D03*
X938338Y529107D03*
X938579Y551379D03*
X938623Y556600D03*
X956100Y516500D03*
X867299Y508600D03*
Y504700D03*
X935490Y519550D03*
X884801Y630225D03*
X892400Y633700D03*
X878740Y643190D03*
Y651190D03*
X870200Y631500D03*
X867260Y608600D03*
X883030Y611940D03*
X878600Y615600D03*
X879600Y621600D03*
X878400Y626200D03*
X874706Y752583D03*
X924484Y812558D03*
X921047Y811463D03*
X869989Y818847D03*
X931800Y791500D03*
X870001Y822862D03*
X934800Y795300D03*
X916855Y810934D03*
X909144Y803346D03*
X903700Y803200D03*
X912762Y792801D03*
X903221Y793938D03*
X912030Y787650D03*
X907800Y788700D03*
X913059Y810367D03*
X906166Y812784D03*
X902560Y813313D03*
X876862Y842155D03*
X881702Y838859D03*
X874593Y763800D03*
X874821Y767690D03*
X931380Y821500D03*
X935485Y821400D03*
X903572Y773740D03*
X931206Y845756D03*
X920170Y857430D03*
X903500Y769900D03*
X939500Y842400D03*
X924670Y857430D03*
X953000Y842400D03*
X911080Y857420D03*
X948500Y842400D03*
X881216Y813813D03*
X910807Y766589D03*
X904484Y786109D03*
X876256Y798895D03*
X874500Y779100D03*
X866655Y855100D03*
X870200Y852203D03*
X872600Y798700D03*
X943294Y838833D03*
X903300Y763200D03*
X894317Y865406D03*
X890117D03*
X894317Y861206D03*
X890117D03*
X879667Y877303D03*
X884684Y877406D03*
X927260Y922470D03*
X909760Y925445D03*
X922760Y922470D03*
X958256Y894438D03*
X930310Y858550D03*
X879770Y868369D03*
X895500Y1038000D03*
X891600Y980000D03*
X888000D03*
X886400Y976500D03*
X893600D03*
X897200D03*
X895200Y980000D03*
X890000Y976500D03*
X951500Y1117500D03*
X947000D03*
X943000D03*
X949500Y1114500D03*
X954500D03*
X956500Y1117500D03*
X890500Y1201200D03*
X885930Y1210537D03*
X892460Y1211340D03*
X887200Y1216460D03*
X893200Y1203660D03*
X888825Y1208263D03*
X889965Y1213936D03*
X884677Y1219029D03*
X947700Y1185500D03*
X947500Y1233000D03*
X955500D03*
X926700Y1199000D03*
X952500Y1193300D03*
X869937Y1400312D03*
X941559Y1408198D03*
Y1403198D03*
X866000Y1398000D03*
X945415Y1429318D03*
X945414Y1412818D03*
X1038067Y441886D03*
X1021890Y439717D03*
X991538Y522018D03*
X1000051Y547644D03*
X974530Y559550D03*
X974550Y563690D03*
X1003591Y552081D03*
X996998Y539555D03*
X971420Y537950D03*
X975910Y537770D03*
X990200Y544250D03*
X995213Y529837D03*
X998905Y529824D03*
X986638Y519684D03*
X991360Y529780D03*
X963870Y754152D03*
X1050774Y815327D03*
X1050650Y825420D03*
X1022838Y829101D03*
X1042545Y832026D03*
X1015950Y838000D03*
X1026932Y841614D03*
X1050082Y843729D03*
X993400Y833250D03*
X969926Y847638D03*
X971197Y775799D03*
X977676Y828513D03*
X1005272Y837091D03*
X1000827Y837072D03*
X973070Y828512D03*
X1027524Y948954D03*
X1039500Y891100D03*
X1037110Y859471D03*
X989100Y899600D03*
X972042Y884600D03*
X985542Y882900D03*
X989742D03*
X996938Y901170D03*
X1034200Y945000D03*
X1040200D03*
X1046272Y944928D03*
X1039500Y874700D03*
X1024129Y946152D03*
X1044800Y893750D03*
X1030862Y951946D03*
X1022080Y960728D03*
X1008739Y1096000D03*
X961000Y1117500D03*
X1029500Y1104900D03*
X1028500Y1118601D03*
X1030178Y1134165D03*
X965500Y1128000D03*
X1012800Y1122100D03*
X1002671Y1124700D03*
X1029000Y1122400D03*
X977643Y1132490D03*
X1007431Y1122900D03*
X1026100Y1145996D03*
X1014500Y1153500D03*
X1012000Y1150000D03*
X1017500D03*
X1020000Y1153500D03*
X982500Y1201000D03*
Y1197000D03*
Y1213000D03*
Y1221000D03*
Y1225000D03*
Y1205000D03*
X964550Y1190200D03*
X1054918Y1330439D03*
Y1325739D03*
X1024193Y1422899D03*
X1010943Y1413899D03*
X1005943Y1406700D03*
X975443Y1407700D03*
X992443Y1406700D03*
X1000443D03*
X988443D03*
X996443Y1406800D03*
X983943Y1407399D03*
X979443Y1406999D03*
X964810Y1421172D03*
X1037400Y1400600D03*
X1031400Y1399200D03*
X1054918Y1386039D03*
Y1353539D03*
Y1358239D03*
Y1381339D03*
X966985Y1393900D03*
X961857D03*
X996693Y1421399D03*
X988693D03*
X1047000Y1421800D03*
X1039900Y1417000D03*
X1002118Y1471365D03*
X998325Y1471434D03*
X992443Y1441399D03*
X1002443D03*
X997443Y1436399D03*
Y1446399D03*
Y1441399D03*
X965443Y1436399D03*
X987576Y1451454D03*
Y1455054D03*
X982343Y1446620D03*
Y1440115D03*
X961877Y1445347D03*
Y1441451D03*
X999443Y1458006D03*
X1049260Y1466691D03*
X1017618Y1470865D03*
X993830Y1471364D03*
X1017618Y1460865D03*
X1043606Y1437906D03*
X962136Y1431831D03*
X1033253Y1444649D03*
X1048553Y1448399D03*
X1035526Y1455899D03*
X1041176Y1455500D03*
X1020500Y1500014D03*
X1037550Y1475814D03*
X1136100Y460288D03*
X1147440Y473040D03*
X1143720Y468520D03*
X1143420Y472900D03*
X1139590Y468380D03*
X1139330Y472820D03*
X1135410Y468380D03*
X1135310Y472820D03*
X1130800Y472900D03*
X1131800Y446800D03*
X1136000Y446849D03*
X1092000Y448400D03*
X1088000Y448500D03*
X1103100Y457300D03*
X1095100Y455800D03*
X1113593Y476094D03*
X1149964Y481623D03*
X1102677Y487116D03*
X1119242Y477261D03*
X1134600Y618747D03*
X1118505Y658863D03*
X1114905Y658882D03*
X1129500Y619200D03*
X1138900Y584900D03*
X1125025Y621993D03*
X1056116Y697100D03*
X1057826Y680233D03*
X1059927Y688329D03*
X1064216Y683751D03*
X1067554Y694447D03*
X1071179Y682315D03*
X1112682Y681223D03*
X1107674Y677776D03*
X1141230Y673825D03*
X1103770Y675413D03*
X1075706Y941261D03*
X1141370Y905550D03*
X1058800Y893750D03*
X1093588Y972000D03*
X1110600Y964200D03*
X1108500Y960600D03*
X1104600Y967800D03*
X1101950Y962900D03*
X1101600Y953700D03*
X1087962Y959252D03*
X1068569Y1191530D03*
X1072931Y1191482D03*
X1072900Y1204500D03*
X1084571Y1200129D03*
X1072600Y1211400D03*
X1084400Y1204200D03*
X1083100Y1305600D03*
X1082080Y1299375D03*
X1126820Y1288500D03*
X1075030Y1323078D03*
X1078850Y1287900D03*
X1082080Y1309495D03*
X1123000Y1297600D03*
X1096280Y1288150D03*
X1092475Y1287971D03*
X1133480Y1296700D03*
Y1291700D03*
X1121346Y1307385D03*
Y1311385D03*
X1117000Y1332500D03*
Y1328500D03*
X1072120Y1299375D03*
Y1304495D03*
Y1309495D03*
Y1292460D03*
X1067712Y1384766D03*
X1099112Y1391273D03*
X1099100Y1375200D03*
X1099112Y1383273D03*
X1099100Y1371200D03*
X1117362Y1406073D03*
X1134112Y1363273D03*
X1122112D03*
X1091000Y1393500D03*
X1086646Y1396419D03*
X1126112Y1401773D03*
X1160900Y468500D03*
X1156110Y473330D03*
X1152600Y468470D03*
X1245567Y420602D03*
X1243500Y393600D03*
X1201000Y447000D03*
X1200500Y452000D03*
X1150900Y485100D03*
X1177100Y495300D03*
X1167000Y586500D03*
X1232490Y664290D03*
X1236690D03*
X1171700Y603700D03*
X1172500Y599700D03*
X1169125Y581776D03*
X1166550Y579200D03*
X1177350Y597792D03*
X1212587Y740895D03*
Y736695D03*
Y732495D03*
X1232490Y668490D03*
X1212587Y728295D03*
X1236690Y668490D03*
X1212587Y724095D03*
X1232490Y672690D03*
X1212587Y719895D03*
X1236690Y672690D03*
X1206414Y704261D03*
X1209931Y701608D03*
X1207468Y697962D03*
X1210283Y695565D03*
X1212587Y749295D03*
Y745095D03*
X1232490Y685290D03*
X1179129Y672187D03*
X1232490Y681090D03*
X1190995Y776395D03*
X1186690Y791440D03*
X1217111Y825000D03*
X1173990Y797760D03*
X1177300Y804960D03*
X1180520Y790880D03*
X1179690Y798020D03*
X1157556Y932754D03*
X1184778Y912848D03*
X1180090Y896524D03*
X1181550Y906100D03*
X1184750Y889200D03*
Y896300D03*
X1155600Y1074500D03*
X1193894Y1292533D03*
X1227100D03*
X1205624D03*
X1238830D03*
X1185324Y1286563D03*
X1220450Y1292533D03*
X1216894Y1304283D03*
Y1308283D03*
X1183894Y1304783D03*
Y1308783D03*
X1188894Y1346763D03*
X1222000Y1346700D03*
X1180614Y1340033D03*
X1213820D03*
X1243768Y1376953D03*
X1208394Y1346763D03*
X1193894D03*
X1227100D03*
X1203312Y1402793D03*
X1241600Y1346763D03*
X1169412Y1396873D03*
X1297000Y68500D03*
X1319100Y47400D03*
X1308000Y35000D03*
X1309500Y76500D03*
X1314500D03*
X1299500D03*
X1304500D03*
X1261100Y16600D03*
X1264700Y16400D03*
X1256800Y132400D03*
X1322500Y113500D03*
X1317500D03*
X1327000D03*
X1262600Y119700D03*
X1262945Y377600D03*
X1294624Y358802D03*
X1247949Y423302D03*
X1250648Y425686D03*
X1245959Y435527D03*
X1265295Y421223D03*
X1257000Y434600D03*
X1248500Y393600D03*
X1325500Y504750D03*
X1323000Y566500D03*
X1318000D03*
X1328000D03*
X1300100Y530000D03*
X1326500Y514000D03*
X1312000Y501500D03*
X1272182Y571361D03*
X1334500Y549500D03*
Y554500D03*
Y539500D03*
Y544500D03*
X1247588Y842190D03*
X1325500Y907000D03*
Y957250D03*
X1323000Y1019000D03*
X1318000D03*
X1328000D03*
X1300900Y981800D03*
X1326500Y966500D03*
X1262400Y1024700D03*
X1312000Y954000D03*
X1260000Y993500D03*
X1334500Y1002000D03*
Y1007000D03*
Y992000D03*
Y997000D03*
X1273874Y1423000D03*
X1314375Y1424375D03*
X1327900Y1416500D03*
X1266914Y1394873D03*
X1258187Y1389753D03*
X1281624Y1409209D03*
X1253165Y1384633D03*
X1246949Y1379513D03*
X1263642Y1392313D03*
X1261224Y1387193D03*
X1277624Y1409209D03*
X1250347Y1382073D03*
X1289574Y1483700D03*
X1252674Y1496800D03*
X1266474Y1487500D03*
X1278574Y1488700D03*
X1282374Y1445500D03*
Y1464000D03*
X1296374Y1430700D03*
X1297089Y1450307D03*
X1322000Y1430700D03*
X1284624Y1476400D03*
X1253374Y1470000D03*
X1260574Y1445600D03*
X1256474Y1446000D03*
X1435750Y73750D03*
X1436000Y48500D03*
X1376700Y136000D03*
X1394200Y113700D03*
X1341324Y372244D03*
X1367514Y397100D03*
X1362514D03*
X1424500Y529100D03*
X1436000Y501500D03*
X1345215Y533601D03*
X1383952Y573102D03*
X1341324Y825000D03*
X1367500Y851922D03*
X1362500D03*
X1424400Y982000D03*
X1386900Y1024600D03*
X1383200Y992700D03*
X1436000Y954000D03*
X1347400Y1416200D03*
X1450500Y61000D03*
X1458500Y86500D03*
Y91500D03*
X1501300Y136100D03*
X1447000Y113500D03*
X1442000D03*
X1452000D03*
X1511400Y119500D03*
X1458500Y96500D03*
Y101500D03*
X1465536Y372244D03*
X1492014Y397100D03*
X1487014D03*
X1449500Y504750D03*
X1447000Y566500D03*
X1442000D03*
X1452000D03*
X1450500Y514000D03*
X1458500Y544500D03*
Y539500D03*
Y554500D03*
Y549500D03*
X1511200Y572300D03*
X1465536Y825000D03*
X1493500Y853100D03*
X1487000Y851600D03*
X1443992Y904962D03*
X1450100Y959500D03*
X1447000Y1019000D03*
X1442000D03*
X1452000D03*
X1450500Y966500D03*
X1511400Y1024600D03*
X1506000Y993000D03*
X1458500Y1002000D03*
Y1007000D03*
Y992000D03*
Y997000D03*
X1548279Y69309D03*
X1575400Y50750D03*
X1557500Y35000D03*
X1549000Y76500D03*
X1554000D03*
X1564000D03*
X1559000D03*
X1625300Y136000D03*
X1596400Y135600D03*
Y131100D03*
Y126100D03*
X1616100Y203786D03*
X1589749Y372244D03*
X1611014Y397100D03*
X1616014D03*
X1574000Y504750D03*
X1571500Y566500D03*
X1566500D03*
X1576500D03*
X1548400Y528800D03*
X1575000Y514000D03*
X1560500Y501500D03*
X1583000Y544500D03*
Y539500D03*
Y554500D03*
Y549500D03*
X1591400Y825000D03*
X1616000Y850100D03*
X1611000D03*
X1572900Y902900D03*
X1574000Y957250D03*
X1571500Y1019000D03*
X1566500D03*
X1576500D03*
X1575000Y966500D03*
X1548900Y981500D03*
X1560500Y954000D03*
X1583000Y997000D03*
Y992000D03*
Y1007000D03*
Y1002000D03*
X1699000Y61000D03*
X1672900Y76400D03*
X1684500Y48500D03*
X1692200Y86200D03*
Y91200D03*
X1690400Y114100D03*
X1695400D03*
X1700400D03*
X1635300Y119600D03*
X1692300Y96100D03*
X1707000Y103500D03*
X1712525Y191268D03*
X1709496Y463382D03*
X1717859Y463907D03*
X1714026Y464191D03*
X1711199Y453177D03*
X1708359Y449207D03*
X1706859Y445207D03*
X1698000Y504750D03*
X1695500Y566500D03*
X1690500D03*
X1700500D03*
X1673200Y529000D03*
X1699000Y514000D03*
X1684500Y501500D03*
X1707083Y543435D03*
Y538435D03*
X1706800Y556300D03*
X1706935Y548158D03*
X1634200Y572200D03*
X1713961Y825000D03*
X1709500Y900700D03*
X1698000Y957250D03*
X1695500Y1019000D03*
X1690500D03*
X1700500D03*
X1699000Y966500D03*
X1672800Y981200D03*
X1635100Y1024700D03*
X1631500Y994000D03*
X1684500Y954000D03*
X1707000Y997000D03*
Y992000D03*
Y1007000D03*
Y1002000D03*
X1676511Y1292495D03*
X1651906Y1428973D03*
X1719726Y1402700D03*
X1716026Y1416500D03*
X1663906Y1428973D03*
X1659906D03*
X1656250Y1461250D03*
X1662626Y1464000D03*
Y1445500D03*
X1674926Y1447400D03*
X1676626Y1432000D03*
X1702501Y1434000D03*
X1661626Y1480000D03*
X1799094Y82033D03*
X1811600Y32800D03*
X1794300Y63400D03*
X1796300Y85600D03*
X1806300D03*
X1811300D03*
X1801300D03*
X1803620Y57000D03*
X1807500Y57400D03*
X1749700Y135600D03*
X1759600Y119500D03*
X1805142Y372600D03*
X1723896Y474582D03*
X1753631Y405830D03*
X1735014Y397100D03*
X1740014D03*
X1755159Y469723D03*
X1740906Y465239D03*
X1746859Y465707D03*
X1724096Y464344D03*
X1746959Y459107D03*
X1742758Y456059D03*
X1814500Y566500D03*
X1797400Y528800D03*
X1742859Y484707D03*
X1808500Y501500D03*
X1759750Y587000D03*
X1740000Y850100D03*
X1735000D03*
X1798300Y908900D03*
X1817263Y919025D03*
X1815310Y899557D03*
X1783900Y897700D03*
X1792263Y898225D03*
X1798500Y898662D03*
X1788430Y898509D03*
X1817739Y889758D03*
X1785603Y887495D03*
X1782763Y883525D03*
X1781263Y879525D03*
X1814500Y1019000D03*
X1796900Y981100D03*
X1759300Y1024900D03*
X1808500Y954000D03*
X1756000Y993500D03*
X1735126Y1416300D03*
X1810426Y1476200D03*
X1790226Y1469300D03*
X1800326Y1445800D03*
X1794426Y1446400D03*
X1868600Y68922D03*
X1872900Y49000D03*
X1870607Y75897D03*
X1823300Y88600D03*
X1845900Y77300D03*
X1840900D03*
X1850800Y77200D03*
X1860500Y38100D03*
X1863950Y45400D03*
X1859050Y19000D03*
X1885508Y77413D03*
X1891300Y49400D03*
X1880500Y48900D03*
X1842400Y29500D03*
X1875500Y87000D03*
X1880500D03*
X1865500D03*
X1870500D03*
X1834018Y169783D03*
X1823500Y113500D03*
X1819134Y109132D03*
X1819000Y113500D03*
X1827114Y397900D03*
X1832114D03*
X1836476Y467034D03*
X1822000Y504750D03*
X1848500Y504000D03*
X1819500Y566500D03*
X1824500D03*
X1855750Y540000D03*
X1839750Y530250D03*
X1841500Y558000D03*
X1846000D03*
X1850500D03*
X1823000Y514000D03*
X1883300Y530000D03*
X1853000Y504000D03*
X1870500Y540500D03*
X1865500D03*
X1880500D03*
X1875500D03*
X1831000Y544500D03*
Y539500D03*
Y554500D03*
Y549500D03*
X1838174Y825000D03*
X1859500Y850100D03*
X1864500D03*
X1820700Y940600D03*
X1848500Y940200D03*
X1829563Y904041D03*
X1828763Y865025D03*
X1821263Y900025D03*
X1821363Y893425D03*
X1822000Y957250D03*
X1848500Y957000D03*
X1850500Y1011000D03*
X1846000D03*
X1841500D03*
X1819500Y1019000D03*
X1824500D03*
X1855750Y993000D03*
X1823000Y966500D03*
X1839750Y983000D03*
X1875800Y981000D03*
X1853000Y957000D03*
X1865500Y993000D03*
X1881814Y993136D03*
X1876814D03*
X1871814D03*
X1831000Y1002000D03*
Y1007000D03*
Y992000D03*
Y997000D03*
X1827600Y970700D03*
X1824826Y1470900D03*
X1822326Y1481600D03*
X1919000Y51000D03*
X1922400Y470400D03*
X1923600Y913525D03*
X1914500Y902000D03*
X1918800Y1112100D03*
G54D34*
X862205Y277953D03*
X848032D03*
X833859D03*
X862205Y272441D03*
X848032D03*
X833859D03*
X862205Y263779D03*
X848032D03*
X833859D03*
X862205Y258268D03*
X848032D03*
X833859D03*
X855118Y282677D03*
X840945D03*
X826772D03*
X855118Y277165D03*
X840945D03*
X826772D03*
X855118Y268504D03*
X840945D03*
X826772D03*
X855118Y262992D03*
X840945D03*
X826772D03*
X862205Y306299D03*
X848032D03*
X833859D03*
X862205Y300787D03*
X848032D03*
X833859D03*
X862205Y292126D03*
X848032D03*
X833859D03*
X862205Y286614D03*
X848032D03*
X833859D03*
X855118Y311023D03*
X840945D03*
X826772D03*
X855118Y305512D03*
X840945D03*
X826772D03*
X855118Y296850D03*
X840945D03*
X826772D03*
X855118Y291338D03*
X840945D03*
X826772D03*
X904725Y272835D03*
Y277165D03*
Y282677D03*
X911811Y272441D03*
Y277953D03*
Y282283D03*
X904725Y262992D03*
Y268504D03*
X911811Y253937D03*
Y258268D03*
Y263779D03*
Y268110D03*
X897638Y282283D03*
Y272441D03*
Y277953D03*
Y253937D03*
Y268110D03*
Y258268D03*
Y263779D03*
X890552Y272835D03*
Y277165D03*
Y282677D03*
Y262992D03*
Y268504D03*
X876378Y277953D03*
Y272441D03*
Y263779D03*
Y258268D03*
X869292Y282677D03*
Y277165D03*
Y268504D03*
Y262992D03*
X904725Y305512D03*
Y311023D03*
Y315354D03*
X911811Y306299D03*
Y310630D03*
X904725Y301181D03*
X911811Y300787D03*
X904725Y287008D03*
Y291338D03*
Y296850D03*
X911811Y286614D03*
Y292126D03*
Y296457D03*
X897638Y306299D03*
Y296457D03*
Y286614D03*
Y292126D03*
Y300787D03*
X890552Y305512D03*
Y311023D03*
Y287008D03*
Y301181D03*
Y291338D03*
Y296850D03*
X876378Y306299D03*
Y300787D03*
Y292126D03*
Y286614D03*
X869292Y311023D03*
Y305512D03*
Y296850D03*
Y291338D03*
X1095420Y520057D03*
X1100932D03*
X1109593D03*
X1115105D03*
X1123766D03*
X1129278D03*
X1099357Y527143D03*
X1104869D03*
X1113530D03*
X1119042D03*
X1127703D03*
X1133215D03*
X1095420Y534230D03*
X1100932D03*
X1109593D03*
X1115105D03*
X1123766D03*
X1129278D03*
X1099357Y541317D03*
X1104869D03*
X1113530D03*
X1119042D03*
X1127703D03*
X1133215D03*
X1095420Y548403D03*
X1100932D03*
X1109593D03*
X1115105D03*
X1123766D03*
X1129278D03*
X1099357Y555490D03*
X1104869D03*
X1113530D03*
X1119042D03*
X1127703D03*
X1133215D03*
X1095420Y562576D03*
X1100932D03*
X1109593D03*
X1115105D03*
X1123766D03*
X1129278D03*
X1099357Y569663D03*
X1104869D03*
X1113530D03*
X1119042D03*
X1127703D03*
X1133215D03*
X1095420Y691711D03*
Y705884D03*
Y720057D03*
Y734230D03*
Y748403D03*
Y762577D03*
X1100932Y691711D03*
Y705884D03*
Y720057D03*
Y734230D03*
Y748403D03*
Y762577D03*
X1109593Y691711D03*
Y705884D03*
Y720057D03*
Y734230D03*
Y748403D03*
Y762577D03*
X1115105Y691711D03*
Y705884D03*
Y720057D03*
Y734230D03*
Y748403D03*
Y762577D03*
X1123766Y691711D03*
Y705884D03*
Y720057D03*
Y734230D03*
Y748403D03*
Y762577D03*
X1129278Y691711D03*
Y705884D03*
Y720057D03*
Y734230D03*
Y748403D03*
Y762577D03*
X1099357Y698797D03*
Y712970D03*
Y727144D03*
Y741317D03*
Y755490D03*
X1104869Y698797D03*
Y712970D03*
Y727144D03*
Y741317D03*
Y755490D03*
X1113530Y698797D03*
Y712970D03*
Y727144D03*
Y741317D03*
Y755490D03*
X1119042Y698797D03*
Y712970D03*
Y727144D03*
Y741317D03*
Y755490D03*
X1127703Y698797D03*
Y712970D03*
Y727144D03*
Y741317D03*
Y755490D03*
X1133215Y698797D03*
Y712970D03*
Y727144D03*
Y741317D03*
Y755490D03*
X1095420Y776750D03*
Y790923D03*
Y805096D03*
Y819270D03*
Y833443D03*
Y847616D03*
X1100932Y776750D03*
Y790923D03*
Y805096D03*
Y819270D03*
Y833443D03*
Y847616D03*
X1109593Y776750D03*
Y790923D03*
Y805096D03*
Y819270D03*
Y833443D03*
Y847616D03*
X1115105Y776750D03*
Y790923D03*
Y805096D03*
Y819270D03*
Y833443D03*
Y847616D03*
X1123766Y776750D03*
Y790923D03*
Y805096D03*
Y819270D03*
Y833443D03*
Y847616D03*
X1129278Y776750D03*
Y790923D03*
Y805096D03*
Y819270D03*
Y833443D03*
Y847616D03*
X1099357Y769663D03*
Y783836D03*
Y798010D03*
Y812183D03*
Y826356D03*
Y840529D03*
Y854703D03*
X1104869Y769663D03*
Y783836D03*
Y798010D03*
Y812183D03*
Y826356D03*
Y840529D03*
Y854703D03*
X1113530Y769663D03*
Y783836D03*
Y798010D03*
Y812183D03*
Y826356D03*
Y840529D03*
Y854703D03*
X1119042Y769663D03*
Y783836D03*
Y798010D03*
Y812183D03*
Y826356D03*
Y840529D03*
Y854703D03*
X1127703Y769663D03*
Y783836D03*
Y798010D03*
Y812183D03*
Y826356D03*
Y840529D03*
Y854703D03*
X1133215Y769663D03*
Y783836D03*
Y798010D03*
Y812183D03*
Y826356D03*
Y840529D03*
Y854703D03*
X1095420Y861789D03*
Y875962D03*
Y890136D03*
Y904309D03*
Y918482D03*
Y932655D03*
X1100932Y861789D03*
Y875962D03*
Y890136D03*
Y904309D03*
Y918482D03*
Y932655D03*
X1109593Y861789D03*
Y875962D03*
Y890136D03*
Y904309D03*
Y918482D03*
Y932655D03*
X1115105Y861789D03*
Y875962D03*
Y890136D03*
Y904309D03*
Y918482D03*
Y932655D03*
X1123766Y861789D03*
Y875962D03*
Y890136D03*
Y904309D03*
Y918482D03*
Y932655D03*
X1129278Y861789D03*
Y875962D03*
Y890136D03*
Y904309D03*
Y918482D03*
Y932655D03*
X1099357Y868876D03*
Y883049D03*
Y897222D03*
Y911396D03*
Y925569D03*
Y939742D03*
X1104869Y868876D03*
Y883049D03*
Y897222D03*
Y911396D03*
Y925569D03*
Y939742D03*
X1113530Y868876D03*
Y883049D03*
Y897222D03*
Y911396D03*
Y925569D03*
Y939742D03*
X1119042Y868876D03*
Y883049D03*
Y897222D03*
Y911396D03*
Y925569D03*
Y939742D03*
X1127703Y868876D03*
Y883049D03*
Y897222D03*
Y911396D03*
Y925569D03*
Y939742D03*
X1133215Y868876D03*
Y883049D03*
Y897222D03*
Y911396D03*
Y925569D03*
Y939742D03*
G54D15*
X26300Y873700D03*
Y864100D03*
Y868900D03*
X21500Y873700D03*
Y864100D03*
Y868900D03*
X127600Y437500D03*
Y432700D03*
X122800Y437500D03*
Y432700D03*
X127600Y427900D03*
X122800D03*
X169215Y876085D03*
Y880885D03*
X154215D03*
Y876085D03*
X169215Y895685D03*
Y890885D03*
X154215Y895685D03*
Y890885D03*
X164200Y885700D03*
X158900D03*
X192963Y888625D03*
Y883625D03*
X188163Y888625D03*
X183363D03*
X178563D03*
Y883625D03*
X173763D03*
Y888625D03*
X183363Y883625D03*
X188163D03*
X113363Y884925D03*
X180000Y1424000D03*
Y1430000D03*
X186000Y1424000D03*
Y1430000D03*
X152000Y1377000D03*
Y1383000D03*
X158000Y1377000D03*
Y1383000D03*
X170000D03*
Y1377000D03*
X164000Y1383000D03*
Y1377000D03*
X251200Y457900D03*
Y438300D03*
Y443100D03*
Y453100D03*
X291500Y451100D03*
Y446100D03*
X286700D03*
Y451100D03*
X281900D03*
Y446100D03*
X272300D03*
Y451100D03*
X277100Y446100D03*
Y451100D03*
X267752Y458160D03*
Y438560D03*
Y443360D03*
Y453360D03*
X257127Y448364D03*
X261927D03*
X211590Y427289D03*
X211190Y447189D03*
X197763Y888625D03*
Y883625D03*
X296300Y446100D03*
Y451100D03*
X513917Y1447297D03*
X507917D03*
X519717D03*
X826843Y419764D03*
Y424564D03*
Y429364D03*
X802843Y419664D03*
X807643D03*
X822043Y419764D03*
X802843Y429264D03*
Y424464D03*
X807643D03*
Y429264D03*
X822043Y429364D03*
Y424564D03*
X822400Y587368D03*
Y582568D03*
X817600D03*
Y587368D03*
X803200Y587268D03*
Y582468D03*
X798400D03*
Y587268D03*
X822400Y577768D03*
X817600D03*
X803200Y577668D03*
X798400D03*
X808300Y1227168D03*
Y1222368D03*
X813100D03*
Y1227168D03*
X794100D03*
Y1222368D03*
X789300D03*
Y1227168D03*
X813100Y1217568D03*
X808300D03*
X789300D03*
X794100D03*
X1012000Y371369D03*
X1015537Y365911D03*
X1075627Y374973D03*
X1075829Y380885D03*
X1119877Y423540D03*
Y428340D03*
Y418740D03*
X1124677Y428340D03*
Y423540D03*
Y418740D03*
X1105477Y428240D03*
Y423440D03*
X1100677D03*
Y428240D03*
X1105477Y418640D03*
X1100677D03*
X1076142Y386839D03*
X1057400Y771600D03*
X1057600Y776500D03*
X1067200Y786500D03*
X1062400D03*
Y781500D03*
X1057600Y786500D03*
Y781500D03*
X1067200Y791500D03*
X1062400D03*
X1067200Y796500D03*
X1062400D03*
X1057600D03*
Y791500D03*
X1128500Y1225700D03*
X1133300D03*
X1109400Y1221100D03*
X1114200D03*
Y1225900D03*
X1109400D03*
X1133300Y1220900D03*
X1128500D03*
X1133300Y1216100D03*
X1128500D03*
X1109400Y1216300D03*
X1114200D03*
X1117200Y1346700D03*
X1115000Y1485000D03*
X1118000Y1480500D03*
X1112000D03*
X1151100Y1179300D03*
X1155900D03*
X1151100Y1184100D03*
X1155900D03*
Y1188900D03*
X1151100D03*
X1667359Y434407D03*
Y439207D03*
Y429607D03*
X1662559D03*
Y434407D03*
Y439207D03*
X1814463Y449725D03*
Y454725D03*
X1804900Y451800D03*
X1809915Y461785D03*
Y446985D03*
Y456985D03*
Y442185D03*
X1799600Y451800D03*
X1794915Y461785D03*
Y446985D03*
Y456985D03*
Y442185D03*
X1751774Y430510D03*
X1753959Y450607D03*
X1741159Y873707D03*
X1736359D03*
X1741159Y864107D03*
X1736359D03*
X1741159Y868907D03*
X1736359D03*
X1838463Y454725D03*
Y449725D03*
X1819263D03*
Y454725D03*
X1833663D03*
Y449725D03*
X1828863D03*
Y454725D03*
X1824063D03*
Y449725D03*
X1912663Y888925D03*
Y883925D03*
X1869115Y876385D03*
Y891185D03*
Y881185D03*
Y895985D03*
X1873800Y886300D03*
X1884115Y876385D03*
X1898263Y883925D03*
Y888925D03*
X1903063D03*
Y883925D03*
X1907863D03*
Y888925D03*
X1884115Y891185D03*
Y881185D03*
Y895985D03*
X1893463Y888925D03*
Y883925D03*
X1879100Y886300D03*
X1888663Y888925D03*
Y883925D03*
X1828363Y884925D03*
G54D16*
X90709Y1485118D03*
X80709D03*
X70709D03*
X711181D03*
X701181D03*
X691181D03*
X1237953D03*
X1227953D03*
X1217953D03*
X1858425D03*
X1848425D03*
X1838425D03*
G54D22*
X111024Y188130D03*
Y640886D03*
Y1093642D03*
X235236Y188130D03*
Y640886D03*
Y1093642D03*
X359449Y188130D03*
Y640886D03*
Y1093642D03*
X483661Y188130D03*
Y640886D03*
Y1093642D03*
X607874Y188130D03*
Y640886D03*
Y1093642D03*
X732087Y188130D03*
Y640886D03*
Y1093642D03*
X1281693Y188130D03*
Y640886D03*
Y1093642D03*
X1405906Y188130D03*
Y640886D03*
Y1093642D03*
X1530118Y188130D03*
Y640886D03*
Y1093642D03*
X1654331Y188130D03*
Y640886D03*
Y1093642D03*
X1778543Y188130D03*
Y640886D03*
Y1093642D03*
X1902756Y188130D03*
Y640886D03*
Y1093642D03*
G54D18*
X127988Y71319D03*
Y76319D03*
X134983Y61269D03*
Y56769D03*
X127988Y524075D03*
Y529075D03*
X134983Y514025D03*
Y509525D03*
X127988Y976831D03*
Y981831D03*
X134983Y966781D03*
Y962281D03*
X252200Y71319D03*
Y76319D03*
X259195Y61269D03*
Y56769D03*
X252200Y524075D03*
Y529075D03*
X259195Y514025D03*
Y509525D03*
X252200Y976831D03*
Y981831D03*
X259195Y966781D03*
Y962281D03*
X376413Y71319D03*
Y76319D03*
X383408Y61269D03*
Y56769D03*
X376413Y524075D03*
Y529075D03*
X383408Y514025D03*
Y509525D03*
X376413Y976831D03*
Y981831D03*
X383408Y966781D03*
Y962281D03*
X500625Y71319D03*
Y76319D03*
X507620Y61269D03*
Y56769D03*
X500625Y524075D03*
Y529075D03*
X507620Y514025D03*
Y509525D03*
X500625Y976831D03*
Y981831D03*
X507620Y966781D03*
Y962281D03*
X624838Y71319D03*
Y76319D03*
X631833Y61269D03*
Y56769D03*
X624838Y524075D03*
Y529075D03*
X631833Y514025D03*
Y509525D03*
X624838Y976831D03*
Y981831D03*
X631833Y966781D03*
Y962281D03*
X749051Y71319D03*
Y76319D03*
X756046Y61269D03*
Y56769D03*
X749051Y524075D03*
Y529075D03*
X756046Y514025D03*
Y509525D03*
X749051Y976831D03*
Y981831D03*
X756046Y966781D03*
Y962281D03*
X1275400Y68650D03*
X1270400D03*
X1256750Y53650D03*
X1261250D03*
X1275400Y521406D03*
X1270400D03*
X1256750Y506406D03*
X1261250D03*
X1273975Y976831D03*
Y981831D03*
X1257490Y966361D03*
Y961861D03*
X1399613Y68650D03*
X1394613D03*
X1380963Y53650D03*
X1385463D03*
X1399613Y521406D03*
X1394613D03*
X1380963Y506406D03*
X1385463D03*
X1398188Y976831D03*
Y981831D03*
X1381663Y966381D03*
Y961881D03*
X1523825Y68650D03*
X1518825D03*
X1505175Y53650D03*
X1509675D03*
X1523825Y521406D03*
X1518825D03*
X1505175Y506406D03*
X1509675D03*
X1522400Y976831D03*
Y981831D03*
X1505875Y966321D03*
Y961821D03*
X1648038Y68650D03*
X1643038D03*
X1629388Y53650D03*
X1633888D03*
X1648038Y521406D03*
X1643038D03*
X1629388Y506406D03*
X1633888D03*
X1646613Y976831D03*
Y981831D03*
X1630088Y966881D03*
Y962381D03*
X1772250Y68650D03*
X1767250D03*
X1753600Y53650D03*
X1758100D03*
X1772250Y521406D03*
X1767250D03*
X1753600Y506406D03*
X1758100D03*
X1770825Y976831D03*
Y981831D03*
X1754340Y966361D03*
Y961861D03*
X1896463Y68650D03*
X1891463D03*
X1877813Y53650D03*
X1882313D03*
X1896463Y521406D03*
X1891463D03*
X1877813Y506406D03*
X1882313D03*
X1895038Y976831D03*
Y981831D03*
X1878553Y966361D03*
Y961861D03*
G54D20*
X111024Y39508D03*
Y492264D03*
Y945020D03*
X235236Y39508D03*
Y492264D03*
Y945020D03*
X359449Y39508D03*
Y492264D03*
Y945020D03*
X483661Y39508D03*
Y492264D03*
Y945020D03*
X607874Y39508D03*
Y492264D03*
Y945020D03*
X732087Y39508D03*
Y492264D03*
Y945020D03*
X1281693Y39508D03*
Y492264D03*
Y945020D03*
X1405906Y39508D03*
Y492264D03*
Y945020D03*
X1530118Y39508D03*
Y492264D03*
Y945020D03*
X1654331Y39508D03*
Y492264D03*
Y945020D03*
X1778543Y39508D03*
Y492264D03*
Y945020D03*
X1902756Y39508D03*
Y492264D03*
Y945020D03*
G54D36*
X1002362Y284449D03*
X1014960D03*
X1030709D03*
X1043307D03*
X974015Y261812D03*
X986614D03*
X1002362D03*
X1014960D03*
X1030709D03*
X1043307D03*
X1002362Y278544D03*
X1030709D03*
X974015Y267717D03*
X1002362D03*
X1030709D03*
X974015Y255906D03*
X1002362D03*
X1030709D03*
X1014960Y278544D03*
X1043307D03*
X986614Y267717D03*
X1014960D03*
X1043307D03*
X986614Y255906D03*
X1014960D03*
X1043307D03*
X1002362Y290355D03*
X1030709D03*
X1014960D03*
X1043307D03*
X1101405Y1132638D03*
X1119633D03*
X1108098D03*
X1126326D03*
G54D32*
X233858Y1445275D03*
Y1466929D03*
X614173Y1445275D03*
Y1466929D03*
X1381102Y1445275D03*
Y1466929D03*
X1761417Y1445275D03*
Y1466929D03*
G54D19*
X134983Y65269D03*
Y52769D03*
Y518025D03*
Y505525D03*
Y970781D03*
Y958281D03*
X259195Y65269D03*
Y52769D03*
X203300Y71700D03*
X215100Y62940D03*
X207000Y80500D03*
X259195Y518025D03*
Y505525D03*
Y970781D03*
Y958281D03*
X383408Y65269D03*
Y52769D03*
Y518025D03*
Y505525D03*
Y970781D03*
Y958281D03*
X380780Y1428599D03*
Y1422599D03*
Y1416599D03*
Y1410599D03*
X374780Y1428599D03*
Y1422599D03*
Y1416599D03*
Y1410599D03*
X380780Y1434599D03*
X374780D03*
X454000Y83800D03*
X462100Y62940D03*
X450300Y71700D03*
X507620Y65269D03*
Y52769D03*
Y518025D03*
Y505525D03*
Y970781D03*
Y958281D03*
X542066Y1440238D03*
X537466D03*
X532866D03*
X528798Y1437733D03*
X524722Y1436362D03*
X631833Y65269D03*
Y52769D03*
Y518025D03*
Y505525D03*
Y970781D03*
Y958281D03*
X756046Y65269D03*
Y52769D03*
X704000Y80500D03*
X700300Y71700D03*
X712000Y62940D03*
X756046Y518025D03*
Y505525D03*
Y970781D03*
Y958281D03*
X846950Y645820D03*
Y640820D03*
X859664Y683428D03*
X841309Y796644D03*
X841800Y804499D03*
X786200Y1334100D03*
X794200D03*
X801000Y1333800D03*
X786200Y1326100D03*
X794200D03*
X801000Y1325800D03*
X905100Y777000D03*
X944019Y1452220D03*
X962118Y534117D03*
X1121346Y1315676D03*
Y1319676D03*
X1105100Y1351000D03*
Y1355000D03*
X1099112Y1387273D03*
Y1379273D03*
X1216894Y1318783D03*
Y1314783D03*
X1183894Y1319783D03*
Y1315783D03*
X1236600Y1346763D03*
X1232100D03*
X1217100D03*
X1183894D03*
X1203394D03*
X1198894D03*
X1257490Y970361D03*
Y957861D03*
X1381663Y970381D03*
Y957881D03*
X1505875Y970321D03*
Y957821D03*
X1630088Y970881D03*
Y958381D03*
X1754340Y970361D03*
Y957861D03*
X1884600Y49000D03*
X1878553Y970361D03*
Y957861D03*
G54D11*
X78000Y44000D03*
X38000Y86000D03*
X100412Y6000D03*
X95412D03*
X90412D03*
X85412D03*
X80412D03*
X75412D03*
X70412D03*
X65412D03*
X60412D03*
X55412D03*
X50412D03*
X45412D03*
X40412D03*
X35412D03*
X30412D03*
X25412D03*
X20412D03*
X15412D03*
X10412D03*
X6000Y6588D03*
Y11588D03*
Y16588D03*
Y21588D03*
Y26588D03*
Y31588D03*
Y36588D03*
Y41588D03*
Y46588D03*
Y51588D03*
Y56588D03*
Y61588D03*
Y66588D03*
Y71588D03*
Y76588D03*
Y81588D03*
Y86588D03*
Y91588D03*
X86700Y80700D03*
X92250Y80500D03*
X75000Y73300D03*
X81500Y105000D03*
X48000Y160000D03*
X6000Y96588D03*
Y101588D03*
Y106588D03*
Y111588D03*
Y116588D03*
Y121588D03*
Y126588D03*
Y131588D03*
Y136588D03*
Y141588D03*
Y146588D03*
Y151588D03*
Y156588D03*
Y161588D03*
Y166588D03*
Y171588D03*
Y176588D03*
Y181588D03*
Y186588D03*
X95500Y186000D03*
X89000Y162700D03*
X49500Y140500D03*
X64250Y98500D03*
X73500Y120500D03*
X72900Y133000D03*
X88000Y204000D03*
X76000Y232000D03*
X50000Y200000D03*
X6000Y191588D03*
Y196588D03*
Y201588D03*
Y206588D03*
Y211588D03*
Y216588D03*
Y221588D03*
Y226588D03*
Y231588D03*
Y236588D03*
Y241588D03*
Y246588D03*
Y251588D03*
Y256588D03*
Y261588D03*
Y266588D03*
Y271588D03*
Y276588D03*
Y281588D03*
X38000Y348000D03*
X6000Y286588D03*
Y291588D03*
Y296588D03*
Y301588D03*
Y306588D03*
Y311588D03*
Y316588D03*
Y321588D03*
Y326588D03*
Y331588D03*
Y336588D03*
Y341588D03*
Y346588D03*
Y351588D03*
Y356588D03*
Y361588D03*
Y366588D03*
Y371588D03*
Y376588D03*
X55209Y379278D03*
X38000Y418000D03*
Y452000D03*
X6000Y441588D03*
Y436588D03*
Y431588D03*
Y426588D03*
Y421588D03*
Y416588D03*
Y411588D03*
Y406588D03*
Y386588D03*
Y391588D03*
Y396588D03*
Y401588D03*
Y446588D03*
Y451588D03*
Y456588D03*
Y461588D03*
Y381588D03*
Y466588D03*
Y471588D03*
X65692Y392187D03*
X58728Y393206D03*
X88000Y498000D03*
Y478000D03*
X38000Y544000D03*
X81500Y557500D03*
X6000Y476588D03*
Y481588D03*
Y486588D03*
Y491588D03*
Y496588D03*
Y501588D03*
Y506588D03*
Y511588D03*
Y516588D03*
Y521588D03*
Y526588D03*
Y531588D03*
Y536588D03*
Y541588D03*
Y546588D03*
Y551588D03*
Y556588D03*
Y561588D03*
Y566588D03*
Y571588D03*
X64250Y551000D03*
X86700Y533200D03*
X75000Y525800D03*
X92250Y533000D03*
X40000Y614000D03*
X76000Y642000D03*
X38000Y660000D03*
X6000Y576588D03*
Y581588D03*
Y586588D03*
Y591588D03*
Y596588D03*
Y601588D03*
Y606588D03*
Y611588D03*
Y616588D03*
Y621588D03*
Y626588D03*
Y631588D03*
Y636588D03*
Y641588D03*
Y646588D03*
Y651588D03*
Y656588D03*
Y661588D03*
Y666588D03*
X95500Y638500D03*
X89000Y615200D03*
X73500Y573000D03*
X72800Y585500D03*
X49500Y593000D03*
X92000Y758000D03*
X6000Y671588D03*
Y676588D03*
Y681588D03*
Y686588D03*
Y691588D03*
Y696588D03*
Y701588D03*
Y706588D03*
Y711588D03*
Y716588D03*
Y721588D03*
Y726588D03*
Y731588D03*
Y736588D03*
Y741588D03*
Y746588D03*
Y751588D03*
Y756588D03*
Y761588D03*
X34000Y792000D03*
X100000Y800000D03*
X6000Y766588D03*
Y771588D03*
Y776588D03*
Y781588D03*
Y786588D03*
Y791588D03*
Y796588D03*
Y801588D03*
Y806588D03*
Y811588D03*
Y816588D03*
Y821588D03*
Y826588D03*
Y831588D03*
Y836588D03*
Y841588D03*
Y846588D03*
Y851588D03*
Y856588D03*
X53425Y853600D03*
X46461Y853382D03*
X42942Y831932D03*
X26000Y908000D03*
Y940000D03*
X88000Y946000D03*
X6000Y861588D03*
Y866588D03*
Y871588D03*
Y876588D03*
Y881588D03*
Y886588D03*
Y891588D03*
Y896588D03*
Y901588D03*
Y906588D03*
Y911588D03*
Y916588D03*
Y921588D03*
Y926588D03*
Y931588D03*
Y936588D03*
Y941588D03*
Y946588D03*
Y951588D03*
X81500Y1010500D03*
X38000Y996000D03*
X6000Y956588D03*
Y961588D03*
Y966588D03*
Y971588D03*
Y976588D03*
Y981588D03*
Y986588D03*
Y991588D03*
Y996588D03*
Y1001588D03*
Y1006588D03*
Y1011588D03*
Y1016588D03*
Y1021588D03*
Y1026588D03*
Y1031588D03*
Y1036588D03*
Y1041588D03*
Y1046588D03*
X73500Y1026000D03*
X72600Y1038400D03*
X49500Y1046000D03*
X86700Y986200D03*
X75000Y978800D03*
X64250Y1004000D03*
X92250Y986000D03*
X50000Y1100000D03*
X6000Y1051588D03*
Y1056588D03*
Y1061588D03*
Y1066588D03*
Y1071588D03*
Y1076588D03*
Y1081588D03*
Y1086588D03*
Y1091588D03*
Y1096588D03*
Y1101588D03*
Y1106588D03*
Y1111588D03*
Y1116588D03*
Y1121588D03*
Y1126588D03*
Y1131588D03*
Y1136588D03*
Y1141588D03*
X95500Y1091500D03*
X89000Y1068200D03*
X50000Y1150000D03*
Y1200000D03*
X6000Y1146588D03*
Y1151588D03*
Y1156588D03*
Y1161588D03*
Y1166588D03*
Y1171588D03*
Y1176588D03*
Y1181588D03*
Y1186588D03*
Y1191588D03*
Y1196588D03*
Y1201588D03*
Y1206588D03*
Y1211588D03*
Y1216588D03*
Y1221588D03*
Y1226588D03*
Y1231588D03*
Y1236588D03*
X100000Y1250000D03*
X50000D03*
Y1300000D03*
X100000D03*
X6000Y1321588D03*
Y1326588D03*
Y1331588D03*
Y1286588D03*
Y1291588D03*
Y1296588D03*
Y1301588D03*
Y1306588D03*
Y1311588D03*
Y1316588D03*
Y1241588D03*
Y1246588D03*
Y1251588D03*
Y1256588D03*
Y1261588D03*
Y1266588D03*
Y1271588D03*
Y1276588D03*
Y1281588D03*
X50000Y1350000D03*
X100000D03*
Y1400000D03*
X50000D03*
X6000Y1421588D03*
Y1416588D03*
Y1411588D03*
Y1406588D03*
Y1401588D03*
Y1396588D03*
Y1391588D03*
Y1386588D03*
Y1381588D03*
Y1376588D03*
Y1371588D03*
Y1366588D03*
Y1361588D03*
Y1356588D03*
Y1351588D03*
Y1346588D03*
Y1341588D03*
Y1426588D03*
Y1336588D03*
X86000Y1444000D03*
X6000Y1451588D03*
Y1446588D03*
Y1441588D03*
Y1436588D03*
Y1431588D03*
X99000Y1501000D03*
X61500Y1502000D03*
X87539Y1499118D03*
X82539D03*
X77539D03*
X72539D03*
X67539D03*
X92539D03*
X11000Y1455500D03*
X15500Y1458500D03*
X17811Y1462693D03*
Y1467693D03*
Y1472693D03*
Y1477693D03*
Y1482693D03*
Y1487693D03*
Y1492693D03*
Y1497693D03*
Y1502693D03*
Y1507693D03*
X17500Y1512000D03*
X21819Y1513685D03*
X26819D03*
X31819D03*
X36819D03*
X41819D03*
X46819D03*
X51819D03*
X56819D03*
X58500Y1508000D03*
X144000Y88000D03*
X195412Y6000D03*
X190412D03*
X185412D03*
X180412D03*
X175412D03*
X170412D03*
X165412D03*
X160412D03*
X155412D03*
X150412D03*
X145412D03*
X140412D03*
X135412D03*
X130412D03*
X125412D03*
X120412D03*
X115412D03*
X110412D03*
X105412D03*
X111437Y81319D03*
Y66319D03*
X106937Y84370D03*
Y93819D03*
X111437Y51319D03*
X118437Y27697D03*
X157900Y17900D03*
X157600Y24500D03*
X157400Y35800D03*
X158000Y152000D03*
X154000Y106000D03*
X111437Y161319D03*
Y151319D03*
X173500Y140500D03*
X111437Y131319D03*
Y121319D03*
X127600Y119300D03*
X106937Y103268D03*
X174000Y236000D03*
X118437Y199941D03*
X112000Y316000D03*
X162000Y310000D03*
X150000Y350000D03*
X189342Y378932D03*
X102000Y440000D03*
X174000Y410000D03*
X192861Y400482D03*
X156000Y544000D03*
X130000Y560000D03*
X144000Y550000D03*
X152000Y492000D03*
X160000Y508000D03*
X188250Y550951D03*
X106937Y556024D03*
Y537126D03*
Y546575D03*
X111437Y534075D03*
Y519075D03*
Y504075D03*
X118437Y480453D03*
X180500Y576000D03*
X162000Y614000D03*
X118437Y652697D03*
X111437Y614075D03*
Y604075D03*
Y584075D03*
Y574075D03*
X173500Y593000D03*
X140750Y575500D03*
X174000Y686000D03*
X156000Y768000D03*
X150000Y800000D03*
X176425Y853700D03*
X176558Y831000D03*
X172318Y844782D03*
X136000Y912000D03*
X140000Y938000D03*
X188000Y932000D03*
X118437Y933209D03*
X173763Y907525D03*
X189763D03*
X185763D03*
X181763D03*
X177763D03*
X193763D03*
X180500Y1028500D03*
X160000Y982000D03*
X142000Y1008000D03*
X140750Y1028500D03*
X174000Y1046000D03*
X111437Y1036831D03*
Y1026831D03*
X188750Y1004000D03*
X111437Y956831D03*
Y986831D03*
Y971831D03*
X106937Y1008780D03*
Y989882D03*
Y999331D03*
X136500Y1111500D03*
X164000Y1068000D03*
X118437Y1105453D03*
X111437Y1066831D03*
Y1056831D03*
X158484Y1416000D03*
X139774Y1420600D03*
X131143Y1427661D03*
X102000Y1505500D03*
X177433Y1513685D03*
X182433D03*
X187433D03*
X192433D03*
X147433D03*
X152433D03*
X157433D03*
X162433D03*
X167433D03*
X172433D03*
X103000Y1511000D03*
X107433Y1513685D03*
X112433D03*
X117433D03*
X122433D03*
X127433D03*
X132433D03*
X137433D03*
X157574Y1453500D03*
X145374Y1452500D03*
X145274Y1434685D03*
X156674Y1435085D03*
X167499Y1434000D03*
X104074Y1462500D03*
X114874Y1476700D03*
X118574Y1465900D03*
X121274Y1447400D03*
X142433Y1513685D03*
X262000Y30000D03*
X280000Y90000D03*
X264000Y94000D03*
X290412Y6000D03*
X285412D03*
X280412D03*
X275412D03*
X270412D03*
X265412D03*
X260412D03*
X255412D03*
X250412D03*
X245412D03*
X240412D03*
X235412D03*
X230412D03*
X225412D03*
X220412D03*
X215412D03*
X210412D03*
X205412D03*
X200412D03*
X231000Y82000D03*
X231149Y93819D03*
X235649Y81319D03*
Y66319D03*
Y51319D03*
X242649Y27697D03*
X284000Y160000D03*
X256000Y142000D03*
X235649Y161319D03*
Y151319D03*
X219500Y186000D03*
X213500Y162700D03*
X235649Y131319D03*
Y121319D03*
X231149Y103268D03*
X250900Y119500D03*
X197000Y133000D03*
X197500Y120500D03*
X198000Y198000D03*
X212000Y236000D03*
X288000Y242000D03*
X250000Y250000D03*
X242649Y199941D03*
X214000Y328000D03*
X250000Y350000D03*
Y300000D03*
X291042Y379232D03*
X286000Y422000D03*
X199825Y400700D03*
X271590Y469789D03*
X275590D03*
X279590D03*
X283590D03*
X287590D03*
X291590D03*
X212500Y557500D03*
X216000Y498000D03*
X286000Y490000D03*
Y506000D03*
X268000Y544000D03*
X278000Y554000D03*
X231149Y556024D03*
X232433Y537126D03*
X231149Y546575D03*
X235649Y534075D03*
Y519075D03*
Y504075D03*
X242649Y480453D03*
X210700Y533200D03*
X199000Y525800D03*
X216250Y533000D03*
X286000Y612000D03*
X200000Y646000D03*
X242649Y652697D03*
X235649Y614075D03*
X213500Y615200D03*
X219500Y638500D03*
X235649Y604075D03*
Y584075D03*
Y574075D03*
X268187Y578998D03*
X197200Y585500D03*
X197500Y573000D03*
X250000Y700000D03*
Y750000D03*
Y850000D03*
Y800000D03*
X291042Y831932D03*
X252000Y906000D03*
X212000Y916000D03*
X213500Y951500D03*
X263500Y939500D03*
X242649Y933209D03*
X284500Y982000D03*
X265000Y1008500D03*
X206000Y1010500D03*
X198000Y1026000D03*
X197300Y1038500D03*
X264250Y1028500D03*
X235649Y1036831D03*
Y1026831D03*
X252100Y959100D03*
X211200Y986200D03*
X199500Y978800D03*
X216750Y986000D03*
X231149Y1008780D03*
Y989882D03*
Y999331D03*
X235649Y986831D03*
Y971831D03*
X288000Y1068000D03*
X200000Y1100000D03*
X242649Y1105453D03*
X220000Y1091500D03*
X213500Y1068200D03*
X235649Y1066831D03*
Y1056831D03*
X200000Y1200000D03*
X250000D03*
Y1150000D03*
X200000D03*
X227500Y1303000D03*
X250000Y1350000D03*
X233074Y1429500D03*
X239274Y1429600D03*
X237235Y1419039D03*
X236974Y1425000D03*
X259500Y1494000D03*
X256000Y1466000D03*
X283000Y1492000D03*
X279000Y1498500D03*
X197433Y1513685D03*
X202433D03*
X207433D03*
X212433D03*
X217433D03*
X222433D03*
X227433D03*
X232433D03*
X237433D03*
X242433D03*
X247433D03*
X252433D03*
X257433D03*
X262433D03*
X267433D03*
X272433D03*
X277433D03*
X278646Y1509398D03*
Y1504398D03*
X288685Y1490063D03*
X386000Y28000D03*
X338000Y30000D03*
Y44000D03*
X385412Y6000D03*
X380412D03*
X375412D03*
X370412D03*
X365412D03*
X360412D03*
X355412D03*
X350412D03*
X345412D03*
X340412D03*
X335412D03*
X330412D03*
X325412D03*
X320412D03*
X315412D03*
X310412D03*
X305412D03*
X300412D03*
X295412D03*
X355362Y84370D03*
Y93819D03*
X359862Y81319D03*
Y66319D03*
X323500Y73300D03*
X340750Y80500D03*
X335200Y80700D03*
X359862Y51319D03*
X366862Y27697D03*
X359862Y161319D03*
Y151319D03*
X344000Y186000D03*
X337500Y162700D03*
X298000Y140500D03*
X359862Y131319D03*
X357506Y123493D03*
X355362Y103268D03*
X375500Y119400D03*
X312750Y98500D03*
X322000Y120500D03*
X321500Y133000D03*
X324000Y196000D03*
X366862Y199941D03*
X358000Y318000D03*
X320000Y422000D03*
X336000Y466000D03*
X384000Y468000D03*
X301525Y400900D03*
X294561Y400682D03*
X338000Y498000D03*
X355362Y556024D03*
Y537126D03*
Y546575D03*
X312750Y551000D03*
X359862Y534075D03*
Y519075D03*
Y504075D03*
X366862Y480453D03*
X335200Y533200D03*
X323500Y525800D03*
X340750Y533000D03*
X324000Y650000D03*
X359862Y614075D03*
X366862Y652697D03*
X344000Y638500D03*
X337500Y615200D03*
X359862Y604075D03*
Y584075D03*
X374261Y572963D03*
X322000Y573000D03*
X323380Y589452D03*
X298000Y593000D03*
X334000Y686000D03*
X342000Y758000D03*
X350000Y850000D03*
Y800000D03*
X301525Y853600D03*
X294561Y853382D03*
X337500Y946500D03*
X359500Y925400D03*
X330000Y1010500D03*
X304500Y1028500D03*
X359862Y1036831D03*
Y1026831D03*
X322000Y1026000D03*
X321200Y1038500D03*
X298000Y1046000D03*
X358800Y955900D03*
X355362Y1008780D03*
Y989882D03*
Y999331D03*
X359862Y986831D03*
Y971831D03*
X335200Y986200D03*
X323500Y978800D03*
X312750Y1004000D03*
X340750Y986000D03*
X318000Y1058000D03*
X326000Y1106000D03*
X366862Y1105453D03*
X359862Y1066831D03*
Y1056831D03*
X344000Y1091500D03*
X337500Y1068200D03*
X300000Y1200000D03*
Y1150000D03*
X384055Y1330472D03*
Y1320472D03*
X354055Y1330472D03*
X364055D03*
X354055Y1320472D03*
X364055D03*
X324055Y1330472D03*
X334055D03*
X324055Y1320472D03*
X334055D03*
X304055Y1330472D03*
Y1320472D03*
X294055Y1330472D03*
Y1320472D03*
X384055Y1340472D03*
Y1350472D03*
X354055Y1340472D03*
Y1350472D03*
X364055Y1340472D03*
Y1350472D03*
X324055Y1340472D03*
Y1350472D03*
X334055Y1340472D03*
Y1350472D03*
X304055D03*
Y1340472D03*
X294055Y1350472D03*
Y1340472D03*
X350000Y1400000D03*
X323688Y1357736D03*
X328688D03*
X333688D03*
X338688D03*
X343688D03*
X348688D03*
X353688D03*
X358688D03*
X363688D03*
X368688D03*
X373688D03*
X378688D03*
X383688D03*
X298688D03*
X303688D03*
X308688D03*
X313688D03*
X318688D03*
X293688D03*
X300000Y1400000D03*
X293685Y1490063D03*
X298685D03*
X303685D03*
X308685D03*
X313685D03*
X318685D03*
X323685D03*
X328685D03*
X333685D03*
X338685D03*
X343685D03*
X348685D03*
X353685D03*
X358685D03*
X363685D03*
X368685D03*
X373685D03*
X378685D03*
X383685D03*
X410679Y31098D03*
X414000Y58000D03*
X402000Y64000D03*
X480412Y6000D03*
X475412D03*
X470412D03*
X465412D03*
X460412D03*
X455412D03*
X450412D03*
X445412D03*
X440412D03*
X435412D03*
X430412D03*
X425412D03*
X420412D03*
X415412D03*
X410412D03*
X405412D03*
X400412D03*
X395412D03*
X390412D03*
X479574Y84370D03*
Y93819D03*
X467500Y116000D03*
X394000Y164000D03*
Y174000D03*
X462000Y162700D03*
X468000Y186000D03*
X422000Y140500D03*
X479574Y103268D03*
X441300Y126000D03*
X445500Y133000D03*
X440849Y111648D03*
X388000Y196000D03*
X416000D03*
X400000Y350000D03*
X415542Y378932D03*
X428000Y430000D03*
X460000Y468000D03*
X426025Y400700D03*
X419061Y400382D03*
X402000Y560000D03*
X388000Y548000D03*
X410000Y544000D03*
X392000Y490000D03*
X460000Y496000D03*
X479574Y556024D03*
Y537126D03*
Y546575D03*
X436750Y551000D03*
X459200Y533200D03*
X446993Y527868D03*
X464750Y533000D03*
X410000Y616000D03*
X468000Y638500D03*
X467029Y610775D03*
X441641Y574141D03*
X445546Y586021D03*
X421820Y593641D03*
X389250Y575500D03*
X422000Y684000D03*
X454000Y686000D03*
X466000Y762000D03*
X400000Y800000D03*
X425725Y853400D03*
X418761Y853082D03*
X415242Y831882D03*
X387500Y939000D03*
X462000Y947000D03*
X428500Y1028500D03*
X454000Y1010500D03*
X407000Y984000D03*
X389500Y1009000D03*
X446000Y1026000D03*
X445100Y1038500D03*
X389250Y1028500D03*
X422000Y1046000D03*
X459200Y986200D03*
X447500Y978800D03*
X436750Y1004000D03*
X464750Y986000D03*
X479574Y1008780D03*
Y989882D03*
Y999331D03*
X448000Y1106000D03*
X410000Y1068000D03*
X468000Y1091500D03*
X462000Y1068200D03*
X450000Y1150000D03*
Y1200000D03*
X474055Y1330472D03*
X484055D03*
X474055Y1320472D03*
X484055D03*
X444055Y1330472D03*
X454055D03*
X444055Y1320472D03*
X454055D03*
X414055Y1330472D03*
X424055D03*
X414055Y1320472D03*
X424055D03*
X394055Y1330472D03*
Y1320472D03*
X474055Y1340472D03*
Y1350472D03*
X484055Y1340472D03*
Y1350472D03*
X444055Y1340472D03*
Y1350472D03*
X454055Y1340472D03*
Y1350472D03*
X414055Y1340472D03*
Y1350472D03*
X424055Y1340472D03*
Y1350472D03*
X394055Y1340472D03*
Y1350472D03*
X390500Y1386000D03*
X388688Y1357736D03*
X393688D03*
X462000Y1382985D03*
Y1372985D03*
Y1362985D03*
X474000Y1382985D03*
Y1372985D03*
Y1362985D03*
X426000D03*
X450000Y1372985D03*
Y1382985D03*
X414000Y1372985D03*
X450000Y1362985D03*
X438000Y1372985D03*
X414000Y1362985D03*
X438000D03*
X426000Y1372985D03*
X438000Y1382985D03*
X414000D03*
X426000D03*
X388685Y1490063D03*
X393685D03*
X398685D03*
X403685D03*
X408685D03*
X413685D03*
X418685D03*
X423685D03*
X428685D03*
X433685D03*
X438685D03*
X443685D03*
X448685D03*
X453685D03*
X458685D03*
X463685D03*
X468685D03*
X473685D03*
X478685D03*
X532000Y90000D03*
X534000Y58000D03*
X512000Y28000D03*
X575412Y6000D03*
X570412D03*
X565412D03*
X560412D03*
X555412D03*
X550412D03*
X545412D03*
X540412D03*
X535412D03*
X530412D03*
X525412D03*
X520412D03*
X515412D03*
X510412D03*
X505412D03*
X500412D03*
X495412D03*
X490412D03*
X485412D03*
X572000Y73300D03*
X484074Y81319D03*
Y66319D03*
Y51319D03*
X491074Y27697D03*
X556000Y156000D03*
X568000Y190000D03*
X544000Y160000D03*
X502500Y139500D03*
X512000Y104000D03*
X546500Y140500D03*
X484074Y161319D03*
Y151319D03*
X561250Y98500D03*
X570500Y120500D03*
X569900Y133000D03*
X499900Y119400D03*
X484074Y131319D03*
Y121319D03*
X534000Y222500D03*
X493000Y218500D03*
X491074Y199941D03*
X539742Y379232D03*
X543242Y400682D03*
X550225Y400900D03*
X516000Y488000D03*
X574000D03*
X524000Y560000D03*
X561250Y551000D03*
X572000Y525800D03*
X484074Y504075D03*
X491074Y480453D03*
X483513Y535912D03*
X484074Y519075D03*
X536000Y644000D03*
X510000Y656000D03*
X491074Y652697D03*
X484074Y614075D03*
X565279Y578552D03*
X569900Y585500D03*
X551276Y597925D03*
X483265Y606243D03*
X484074Y584075D03*
Y574075D03*
X513250Y574252D03*
X552000Y686000D03*
X542000Y764000D03*
X500000Y800000D03*
Y850000D03*
X512000Y939000D03*
X483549Y925564D03*
X513500Y1009000D03*
X532000Y983000D03*
X553000Y1028500D03*
X570500Y1026000D03*
X569900Y1038500D03*
X546500Y1046000D03*
X513250Y1028500D03*
X484074Y1036831D03*
Y1026831D03*
X572000Y978800D03*
X561250Y1004000D03*
X499800Y956831D03*
X484074Y986831D03*
Y971831D03*
X534000Y1068000D03*
X550000Y1100000D03*
X491074Y1105453D03*
X484074Y1066831D03*
Y1056831D03*
X500000Y1150000D03*
X550000D03*
Y1200000D03*
X500000D03*
X522000Y1294000D03*
X498000Y1332985D03*
X510000Y1344485D03*
X498000Y1352985D03*
X522000Y1344485D03*
X498000Y1342985D03*
X510000Y1354485D03*
X522000D03*
X510000Y1364485D03*
X522000D03*
X510000Y1374485D03*
Y1384485D03*
X522000Y1374485D03*
Y1384485D03*
X498000Y1382985D03*
Y1372985D03*
X486000Y1382985D03*
Y1372985D03*
X498000Y1362985D03*
X486000D03*
X501000Y1494000D03*
X503000Y1499000D03*
X494500Y1490500D03*
X574937Y1513685D03*
X569937D03*
X564937D03*
X559937D03*
X554937D03*
X549937D03*
X544937D03*
X539937D03*
X534937D03*
X529937D03*
X524937D03*
X483685Y1490063D03*
X488685D03*
X503244Y1504378D03*
Y1509378D03*
X504937Y1513685D03*
X509937D03*
X514937D03*
X528500Y1444600D03*
X519937Y1513685D03*
X500000Y1472000D03*
X507250Y1478000D03*
X585500Y45000D03*
X650000Y84000D03*
X578000Y52000D03*
X592500Y28000D03*
X670412Y6000D03*
X665412D03*
X660412D03*
X655412D03*
X650412D03*
X645412D03*
X640412D03*
X635412D03*
X630412D03*
X625412D03*
X620412D03*
X615412D03*
X610412D03*
X605412D03*
X600412D03*
X595412D03*
X590412D03*
X585412D03*
X580412D03*
X603787Y84370D03*
Y93819D03*
X608287Y81319D03*
Y66319D03*
X589250Y80500D03*
X583700Y80700D03*
X608287Y51319D03*
X615287Y27697D03*
X638000Y104000D03*
X654000Y162500D03*
X664500Y97000D03*
X579000Y105000D03*
X670500Y140500D03*
X608287Y161319D03*
Y151319D03*
X592500Y186000D03*
X586000Y162700D03*
X608287Y131319D03*
Y121319D03*
X603787Y103268D03*
X624000Y119400D03*
X626000Y140000D03*
X652000Y214000D03*
X582500Y266000D03*
X615287Y199941D03*
X586500Y292000D03*
X643000Y317500D03*
X614500Y318500D03*
X639000Y354500D03*
X602500Y365000D03*
X650742Y378932D03*
X661225Y400738D03*
X654261Y400382D03*
X638000Y488000D03*
X644000Y558000D03*
X603787Y556024D03*
Y537126D03*
Y546575D03*
X608287Y534075D03*
Y519075D03*
Y504075D03*
X615287Y480453D03*
X589250Y533000D03*
X583700Y533200D03*
X671000Y648000D03*
X672500Y615500D03*
X615287Y652697D03*
X622687Y614091D03*
X592500Y638500D03*
X586043Y615962D03*
X670500Y593000D03*
X622703Y604103D03*
X623005Y584047D03*
X608287Y574075D03*
X637750Y575500D03*
X590000Y680000D03*
X600000Y770000D03*
X650000D03*
X624000Y846000D03*
X579148Y832411D03*
X666625Y853400D03*
X589805Y854600D03*
X659661Y853082D03*
X582667Y853605D03*
X656142Y831632D03*
X585000Y948000D03*
X636000Y939000D03*
X615287Y933209D03*
X578000Y1010500D03*
X652500Y984500D03*
X625000Y1014500D03*
X653500Y997500D03*
X670500Y1046000D03*
X637750Y1028500D03*
X608287Y1036831D03*
Y1026831D03*
X601800Y955500D03*
X589250Y986000D03*
X603787Y1008780D03*
Y989882D03*
Y999331D03*
X608287Y986831D03*
Y971831D03*
X583700Y986200D03*
X599000Y1115500D03*
X631500Y1112500D03*
X660000Y1068000D03*
X615287Y1105453D03*
X592500Y1091500D03*
X608287Y1066831D03*
Y1056831D03*
X586000Y1068200D03*
X672000Y1146000D03*
X670000Y1196000D03*
X581800Y1376500D03*
Y1384400D03*
Y1392300D03*
Y1360700D03*
Y1368600D03*
Y1352800D03*
Y1344900D03*
X589700Y1392300D03*
Y1400200D03*
Y1344900D03*
Y1352800D03*
Y1384400D03*
Y1376500D03*
Y1368600D03*
Y1360700D03*
X597600Y1400200D03*
Y1408100D03*
Y1360700D03*
Y1368600D03*
Y1392300D03*
Y1376500D03*
Y1384400D03*
Y1352800D03*
Y1344900D03*
X629200D03*
X621300D03*
X613400D03*
X605500D03*
Y1360700D03*
X613400D03*
X621300D03*
X629200D03*
X605500Y1352800D03*
X613400D03*
X621300D03*
X629200D03*
Y1368600D03*
Y1376500D03*
X605500Y1408100D03*
Y1400200D03*
Y1392300D03*
Y1384400D03*
Y1376500D03*
Y1368600D03*
X613400Y1400200D03*
Y1392300D03*
Y1384400D03*
Y1376500D03*
Y1368600D03*
X621300Y1376500D03*
Y1368600D03*
X613400Y1408100D03*
X669937Y1513685D03*
X659937D03*
X654937D03*
X649937D03*
X644937D03*
X639937D03*
X634937D03*
X629937D03*
X624937D03*
X619937D03*
X614937D03*
X609937D03*
X604937D03*
X599937D03*
X594937D03*
X589937D03*
X584937D03*
X579937D03*
X664937D03*
X653000Y1488500D03*
X765412Y6000D03*
X760412D03*
X755412D03*
X750412D03*
X745412D03*
X740412D03*
X735412D03*
X730412D03*
X725412D03*
X720412D03*
X715412D03*
X710412D03*
X705412D03*
X700412D03*
X695412D03*
X690412D03*
X685412D03*
X680412D03*
X675412D03*
X729201Y87285D03*
X727636Y93834D03*
X732500Y81319D03*
Y66319D03*
Y51319D03*
X739500Y27697D03*
X681000Y171500D03*
X732500Y161319D03*
Y151319D03*
X716500Y186000D03*
X710300Y162700D03*
X747290Y118820D03*
X732500Y131319D03*
Y121319D03*
X728000Y103268D03*
X694500Y120500D03*
X694200Y133000D03*
X714000Y240000D03*
X700000Y200000D03*
X732087Y207847D03*
X756000Y326000D03*
X718000Y332000D03*
X704500Y408500D03*
X716000Y568500D03*
X688000Y496000D03*
X728000Y556024D03*
Y537126D03*
Y546575D03*
X688298Y551625D03*
X732500Y504075D03*
X707700Y533200D03*
X696000Y525800D03*
X732500Y519075D03*
X713250Y533000D03*
X732500Y534075D03*
X724600Y487100D03*
X747843Y612115D03*
X739500Y652697D03*
X710300Y635400D03*
Y615200D03*
X748200Y572200D03*
X732500Y574075D03*
X694200Y585500D03*
X732500Y584075D03*
X694500Y573000D03*
X746356Y604075D03*
X710000Y760500D03*
X726500Y681500D03*
X693500Y680000D03*
X712000Y720000D03*
X710000Y950500D03*
X739500Y933209D03*
X677000Y1028500D03*
X702500Y1010500D03*
X753050Y1028500D03*
X694500Y1026000D03*
X694000Y1038500D03*
X732500Y1036831D03*
Y1026831D03*
X730900Y955800D03*
X707700Y986200D03*
X696000Y978800D03*
X685250Y1004000D03*
X713250Y986000D03*
X728000Y1008780D03*
Y989882D03*
Y999331D03*
X732500Y986831D03*
Y971831D03*
X750000Y1084000D03*
X698000Y1102000D03*
X739500Y1105453D03*
X716500Y1091500D03*
X710300Y1068200D03*
X732500Y1066831D03*
Y1056831D03*
X738000Y1152000D03*
X740000Y1202000D03*
X748000Y1170000D03*
X746000Y1218000D03*
X700000Y1150000D03*
X768867Y1311110D03*
Y1335110D03*
Y1327110D03*
Y1319110D03*
Y1383110D03*
Y1359110D03*
Y1367110D03*
Y1351110D03*
Y1343110D03*
Y1391110D03*
Y1399110D03*
Y1375110D03*
X724248Y1465560D03*
X722000Y1503500D03*
X718500Y1500000D03*
X680500Y1503500D03*
X674937Y1513685D03*
X688012Y1499118D03*
X693012D03*
X698012D03*
X703012D03*
X708012D03*
X713012D03*
X724000Y1509500D03*
X725551Y1513685D03*
X730551D03*
X735551D03*
X740551D03*
X745551D03*
X750551D03*
X755551D03*
X760551D03*
X765551D03*
X730500Y1451500D03*
X685850Y1468600D03*
X724000Y1439700D03*
X717600Y1449700D03*
X746832Y1451034D03*
X735232Y1439334D03*
X739332Y1462234D03*
X750867Y1438001D03*
X722200Y1476900D03*
X678500Y1510500D03*
X777465Y93947D03*
Y88947D03*
Y83947D03*
Y78947D03*
Y73947D03*
Y68947D03*
Y63947D03*
Y58947D03*
Y53947D03*
Y48947D03*
Y43947D03*
Y38947D03*
Y33947D03*
Y28947D03*
Y23947D03*
Y18947D03*
Y13947D03*
X778000Y9500D03*
X775412Y6000D03*
X770412D03*
X777465Y183947D03*
Y178947D03*
Y173947D03*
Y168947D03*
Y163947D03*
Y158947D03*
Y153947D03*
Y148947D03*
Y143947D03*
Y138947D03*
Y133947D03*
Y128947D03*
Y123947D03*
Y118947D03*
Y113947D03*
Y108947D03*
Y103947D03*
Y98947D03*
X862205Y282283D03*
X848032D03*
X833859D03*
X862205Y268110D03*
X848032D03*
X833859D03*
X862205Y253937D03*
X848032D03*
X833859D03*
X855118Y272835D03*
X840945D03*
X826772D03*
X771500Y251000D03*
X802000Y263500D03*
X809500Y197500D03*
X805522Y195764D03*
X808961Y201678D03*
Y206678D03*
Y211678D03*
Y216678D03*
Y236678D03*
Y231678D03*
Y226678D03*
Y221678D03*
Y241678D03*
X779022Y190764D03*
X784022Y194764D03*
X800522Y195764D03*
X795522D03*
X790522D03*
X862205Y310630D03*
X848032D03*
X833859D03*
X862205Y296457D03*
X848032D03*
X833859D03*
X855118Y315354D03*
X840945D03*
X826772D03*
X855118Y301181D03*
X840945D03*
X826772D03*
X855118Y287008D03*
X840945D03*
X826772D03*
X804500Y379000D03*
X769500Y431500D03*
X807500Y473700D03*
X834000Y499000D03*
X822841Y662242D03*
X839400Y744920D03*
X833300Y856920D03*
X854973Y780437D03*
X810700Y776500D03*
X818162Y819005D03*
X810659Y767500D03*
X818434Y919985D03*
X820883Y879428D03*
X820900Y888500D03*
X826000Y1004000D03*
X846500Y997500D03*
X827000Y985500D03*
X822470Y981470D03*
X826000Y1062000D03*
X846500Y1055000D03*
X826000Y1094000D03*
Y1128000D03*
X844000Y1092000D03*
Y1128000D03*
X859113Y1283983D03*
X776867Y1311110D03*
Y1335110D03*
Y1327110D03*
Y1319110D03*
X775600Y1302400D03*
X790056Y1297863D03*
X798056D03*
X782056D03*
X860000Y1410843D03*
X842500Y1411343D03*
X776867Y1399110D03*
X790330Y1407929D03*
X782330D03*
X798330D03*
X795000Y1377900D03*
X786600Y1378100D03*
X790950Y1372703D03*
X776867Y1383110D03*
Y1359110D03*
X782950Y1372703D03*
X776867Y1367110D03*
Y1375110D03*
X798950Y1372703D03*
X776867Y1391110D03*
X790223Y1339930D03*
X782223Y1339430D03*
X798223Y1339930D03*
X776867Y1351110D03*
Y1343110D03*
X820000Y1448000D03*
X779500Y1491000D03*
X775000Y1495500D03*
X770551Y1513685D03*
X773528Y1510662D03*
Y1505662D03*
Y1500662D03*
X786803Y1490063D03*
X791803D03*
X796803D03*
X801803D03*
X806803D03*
X811803D03*
X816803D03*
X821803D03*
X826803D03*
X831803D03*
X836803D03*
X841803D03*
X846803D03*
X851803D03*
X856803D03*
X861803D03*
X876378Y282283D03*
Y268110D03*
Y253937D03*
X869292Y272835D03*
X887127Y254031D03*
X897638Y310630D03*
X890552Y315354D03*
X876378Y310630D03*
Y296457D03*
X869292Y315354D03*
Y301181D03*
Y287008D03*
X874858Y757002D03*
X918400Y760750D03*
X915580Y857420D03*
X942500Y797867D03*
X874500Y774500D03*
X879205Y873548D03*
X918369Y923258D03*
X914208Y924279D03*
X883072Y886211D03*
X889458Y907846D03*
X877877Y891277D03*
X940750Y886000D03*
X928250Y885250D03*
X934500Y885156D03*
X948298Y1215500D03*
X943500Y1233000D03*
X951500D03*
X959500D03*
X957000Y1207500D03*
X953100Y1211400D03*
X953000Y1203600D03*
X904000Y1191700D03*
X877400D03*
X928500Y1220700D03*
X884056Y1283981D03*
X871556D03*
X888000Y1424000D03*
X926000Y1420000D03*
X876500Y1410843D03*
X888776Y1402228D03*
X901435Y1402196D03*
X945200Y1398300D03*
Y1393500D03*
X950200Y1394500D03*
X866500Y1392892D03*
X913935Y1402196D03*
X866000Y1452000D03*
X900000Y1450000D03*
X866803Y1490063D03*
X871803D03*
X876803D03*
X881803D03*
X886803D03*
X891803D03*
X896803D03*
X901803D03*
X906803D03*
X911803D03*
X916803D03*
X921803D03*
X926803D03*
X931803D03*
X936803D03*
X941803D03*
X946803D03*
X951803D03*
X956803D03*
X1033046Y379981D03*
X1035000Y370500D03*
X1032924Y374988D03*
X965700Y519617D03*
X968200Y547200D03*
X964200Y855600D03*
X1009600Y851054D03*
X986471Y829716D03*
X1009950Y838000D03*
X1025636Y854819D03*
X1012125Y925875D03*
X1025251Y893000D03*
X1025065Y896965D03*
X1028500Y879500D03*
X1014807Y899075D03*
X1015007Y895000D03*
X974120Y858920D03*
X976242Y884600D03*
X980442Y882900D03*
X993942D03*
X1013231Y1089300D03*
X1001687Y1111499D03*
X1020000Y1230000D03*
X971700Y1193100D03*
X963500Y1233000D03*
X967500D03*
X960900Y1211400D03*
Y1203600D03*
X1035943Y1424649D03*
X1031443Y1426899D03*
X1040127Y1422500D03*
X1022818Y1393489D03*
X997000Y1496000D03*
X993000Y1491500D03*
X961803Y1490063D03*
X966803D03*
X971803D03*
X976803D03*
X981803D03*
X986803D03*
X998126Y1503614D03*
Y1508614D03*
Y1513614D03*
X1003126D03*
X1008126D03*
X1013126D03*
X1018126D03*
X1023126D03*
X1028126D03*
X1033126D03*
X1038126D03*
X1043126D03*
X1048126D03*
X1053126D03*
X1038303Y1441709D03*
X1021818Y1470865D03*
X1021693Y1444649D03*
X993100Y1456550D03*
X1007618Y1477365D03*
X1013418Y1470865D03*
X1027288Y1467441D03*
X1034100Y1500564D03*
X1024175Y1482189D03*
X1089000Y217500D03*
X1150000Y250000D03*
X1100000D03*
X1068734Y195764D03*
X1064500Y197500D03*
X1065055Y201895D03*
Y206895D03*
Y211895D03*
Y216895D03*
X1148734Y195764D03*
X1143734D03*
X1138734D03*
X1133734D03*
X1128734D03*
X1123734D03*
X1118734D03*
X1113734D03*
X1103734D03*
X1098734D03*
X1093734D03*
X1088734D03*
X1083734D03*
X1078734D03*
X1073734D03*
X1098000Y378000D03*
X1136000D03*
X1100000Y350000D03*
Y300000D03*
X1150000D03*
X1144000Y418000D03*
X1093000Y502000D03*
X1137600Y527100D03*
X1137446Y541317D03*
Y555490D03*
Y569663D03*
X1083000Y620000D03*
X1095000D03*
X1112298Y618498D03*
X1137446Y698798D03*
Y712971D03*
Y727144D03*
Y741317D03*
Y755490D03*
Y769663D03*
Y783836D03*
Y798010D03*
Y812183D03*
Y826356D03*
Y840529D03*
Y854703D03*
Y868876D03*
Y883049D03*
Y897222D03*
Y911396D03*
Y925569D03*
Y939742D03*
X1130000Y994000D03*
X1106000D03*
X1138000Y970000D03*
X1084000Y1092000D03*
X1130000Y1154000D03*
X1078000Y1166000D03*
X1080000Y1230000D03*
X1100625Y1292025D03*
X1107000Y1323500D03*
X1114000Y1430000D03*
X1087933Y1411323D03*
X1082933D03*
X1077933D03*
X1095567Y1426057D03*
X1058126Y1513614D03*
X1061675Y1510352D03*
X1065210Y1506817D03*
X1066638Y1472408D03*
Y1467408D03*
Y1462408D03*
Y1457408D03*
Y1452408D03*
Y1447408D03*
Y1442408D03*
X1095567Y1431057D03*
Y1436057D03*
Y1441057D03*
Y1446057D03*
Y1451057D03*
Y1456057D03*
Y1461057D03*
Y1466057D03*
X1096039Y1505861D03*
X1099575Y1509397D03*
X1103110Y1512932D03*
X1107798Y1513685D03*
X1112798D03*
X1117798D03*
X1122798D03*
X1127798D03*
X1132798D03*
X1137798D03*
X1142798D03*
X1147798D03*
X1095567Y1471057D03*
X1066638Y1502408D03*
X1234500Y6000D03*
X1243844D03*
X1238844D03*
X1230409Y7565D03*
Y12565D03*
Y17565D03*
Y22565D03*
Y27565D03*
Y32565D03*
Y37565D03*
Y42565D03*
Y47565D03*
Y52565D03*
Y57565D03*
Y62565D03*
Y67565D03*
Y72565D03*
Y77565D03*
Y82565D03*
Y87565D03*
Y92565D03*
X1238000Y164000D03*
X1230409Y97565D03*
Y102565D03*
Y107565D03*
Y112565D03*
Y117565D03*
Y122565D03*
Y127565D03*
Y132565D03*
Y137565D03*
Y142565D03*
Y147565D03*
Y152565D03*
Y157565D03*
Y162565D03*
Y167565D03*
Y172565D03*
Y177565D03*
Y182565D03*
X1236500Y216000D03*
X1200000Y250000D03*
X1218734Y195764D03*
X1213734D03*
X1208734D03*
X1203734D03*
X1198734D03*
X1193734D03*
X1188734D03*
X1183734D03*
X1178734D03*
X1173734D03*
X1168734D03*
X1163734D03*
X1158734D03*
X1153734D03*
X1218000Y344000D03*
X1225600Y368700D03*
X1200000Y300000D03*
X1190000Y466000D03*
X1184000Y440000D03*
X1206000Y430500D03*
X1169000Y511500D03*
X1188000Y753500D03*
X1180000Y832000D03*
Y848000D03*
X1217089Y846182D03*
X1224088Y844900D03*
X1213611Y831932D03*
X1200337Y912300D03*
X1200407Y918060D03*
X1240000Y1070000D03*
X1176000D03*
X1200000Y1100000D03*
X1178000Y1214000D03*
X1200000Y1200000D03*
Y1150000D03*
X1196000Y1366000D03*
X1212000D03*
X1242000Y1412000D03*
X1226000Y1436000D03*
X1238000Y1444000D03*
X1190000Y1494000D03*
X1156000D03*
X1200000Y1450000D03*
X1245500Y1500500D03*
X1208000Y1502500D03*
X1234783Y1499118D03*
X1229783D03*
X1224783D03*
X1219783D03*
X1214783D03*
X1239783D03*
X1152798Y1513685D03*
X1157798D03*
X1162798D03*
X1167798D03*
X1172798D03*
X1177798D03*
X1182798D03*
X1187798D03*
X1192798D03*
X1197798D03*
X1202798D03*
X1205500Y1509000D03*
X1279400Y68650D03*
X1266400D03*
X1326000Y92000D03*
X1338844Y6000D03*
X1333844D03*
X1328844D03*
X1323844D03*
X1318844D03*
X1313844D03*
X1308844D03*
X1303844D03*
X1298844D03*
X1293844D03*
X1288844D03*
X1283844D03*
X1278844D03*
X1273844D03*
X1268844D03*
X1263844D03*
X1258844D03*
X1253844D03*
X1248844D03*
X1298655Y59926D03*
X1282106Y81319D03*
Y66319D03*
X1299800Y56000D03*
X1278038Y93821D03*
X1278698Y84340D03*
X1307200Y45000D03*
X1289106Y27697D03*
X1282106Y51319D03*
X1303500Y35000D03*
X1262000Y174000D03*
X1313000Y185500D03*
X1314000Y150500D03*
X1282106Y161319D03*
Y151319D03*
X1302500Y152000D03*
X1305000Y185500D03*
X1298500D03*
X1282106Y131319D03*
Y121319D03*
X1266600Y119500D03*
X1262468Y103268D03*
X1272500Y213000D03*
X1307500Y205000D03*
X1338000Y225000D03*
X1289106Y199941D03*
X1252000Y358000D03*
X1294500Y331500D03*
X1278500Y313000D03*
X1259445Y379019D03*
X1337824Y379176D03*
X1317500Y435500D03*
X1316000Y419000D03*
X1269926Y400687D03*
X1262964Y400469D03*
X1281693Y473218D03*
X1279400Y521406D03*
X1266400D03*
X1298500Y562500D03*
X1317500Y533500D03*
X1277606Y546575D03*
Y556024D03*
Y537126D03*
X1307500Y501500D03*
X1299900Y534200D03*
X1311200Y511500D03*
X1282106Y519075D03*
Y534075D03*
Y504075D03*
X1303800Y522500D03*
X1327000Y487000D03*
X1318000Y660000D03*
X1332000Y646000D03*
X1312973Y643128D03*
X1282106Y614075D03*
X1273979Y652690D03*
X1305000Y638500D03*
X1298000Y638300D03*
X1314000Y603500D03*
X1282106Y574075D03*
Y604075D03*
Y584075D03*
X1302500Y605000D03*
X1272211Y575575D03*
X1254000Y748000D03*
X1312000Y812000D03*
X1278000Y810000D03*
X1250000Y820000D03*
X1337824Y832935D03*
X1310000Y860000D03*
X1270000Y868000D03*
X1274000Y933209D03*
X1298000Y1014000D03*
X1318000Y986000D03*
X1266000Y1046000D03*
X1252000Y1010000D03*
X1266400Y1024700D03*
X1282106Y1036831D03*
Y1026831D03*
X1300600Y986800D03*
X1307500Y954000D03*
X1311200Y964000D03*
X1282106Y956831D03*
X1303800Y975000D03*
X1277606Y1008780D03*
Y999331D03*
Y989882D03*
X1282106Y986831D03*
Y971831D03*
X1266000Y1128000D03*
X1264000Y1082000D03*
X1250000Y1100000D03*
X1289106Y1105453D03*
X1314000Y1056000D03*
X1313000Y1091000D03*
X1298500D03*
X1302500Y1057500D03*
X1305000Y1091000D03*
X1282106Y1066831D03*
Y1056831D03*
X1250000Y1200000D03*
Y1150000D03*
X1288000Y1296000D03*
X1274000Y1314000D03*
X1300000Y1388000D03*
X1274000Y1374000D03*
X1318540Y1424331D03*
X1249000Y1504500D03*
X1328464Y1513685D03*
X1333464D03*
X1338464D03*
X1293464D03*
X1298464D03*
X1303464D03*
X1308464D03*
X1313464D03*
X1318464D03*
X1323464D03*
X1250500Y1510500D03*
X1253464Y1513685D03*
X1258464D03*
X1263464D03*
X1268464D03*
X1273464D03*
X1278464D03*
X1283464D03*
X1306625Y1434000D03*
X1303874Y1453750D03*
X1292374Y1452500D03*
X1301534Y1431345D03*
X1289124Y1430700D03*
X1253374Y1459300D03*
X1260874Y1481400D03*
X1264774Y1470700D03*
X1266574Y1452300D03*
X1288464Y1513685D03*
X1403613Y68650D03*
X1390613D03*
X1432000Y30000D03*
X1358000Y91000D03*
X1433844Y6000D03*
X1428844D03*
X1423844D03*
X1418844D03*
X1413844D03*
X1408844D03*
X1403844D03*
X1398844D03*
X1393844D03*
X1388844D03*
X1383844D03*
X1378844D03*
X1373844D03*
X1368844D03*
X1363844D03*
X1358844D03*
X1353844D03*
X1348844D03*
X1343844D03*
X1406319Y66319D03*
Y81319D03*
X1401819Y93819D03*
Y84370D03*
X1435200Y58500D03*
X1427800Y69500D03*
X1406319Y51319D03*
X1413319Y27697D03*
X1431500Y48500D03*
X1392500Y173000D03*
X1389000Y148500D03*
X1422000Y98000D03*
X1346000Y179000D03*
X1351500Y144500D03*
X1406319Y151319D03*
Y161319D03*
X1426500Y152000D03*
X1422500Y185500D03*
X1429000D03*
X1406319Y121319D03*
Y131319D03*
X1401819Y103268D03*
X1391200Y119500D03*
X1428000Y238000D03*
X1388500Y230000D03*
X1394000Y249000D03*
X1397937Y199951D03*
X1373000Y234500D03*
X1388000Y378000D03*
X1400000Y350000D03*
X1378000Y430000D03*
X1376000Y414000D03*
X1436500Y430000D03*
X1341343Y400626D03*
X1348305Y400844D03*
X1403613Y521406D03*
X1390613D03*
X1384000Y554000D03*
X1352000Y516000D03*
X1432000Y482000D03*
X1364000Y492000D03*
X1401819Y546575D03*
Y556024D03*
Y537126D03*
X1406319Y534075D03*
Y519075D03*
Y504075D03*
X1413319Y480453D03*
X1424400Y534200D03*
X1431500Y501500D03*
X1435200Y511500D03*
X1427800Y522500D03*
X1382000Y592000D03*
X1384000Y646000D03*
X1358000Y600000D03*
X1413319Y652697D03*
X1406319Y614075D03*
X1422500Y638500D03*
X1429000D03*
X1406319Y604075D03*
Y584075D03*
Y574075D03*
X1394110Y575530D03*
X1426500Y605000D03*
X1430000Y752000D03*
X1346000Y704000D03*
X1382000Y688000D03*
X1384000Y782000D03*
X1400000Y850000D03*
X1348305Y853600D03*
X1341343Y853382D03*
X1413319Y933209D03*
X1342000Y976000D03*
X1356000Y998000D03*
X1424100Y987000D03*
X1391000Y1024800D03*
X1406319Y1036831D03*
Y1026831D03*
Y956831D03*
X1431500Y954000D03*
X1435200Y964000D03*
X1427800Y975000D03*
X1401819Y1008780D03*
Y999331D03*
Y989882D03*
X1406319Y986831D03*
Y971831D03*
X1360000Y1054000D03*
X1350000Y1100000D03*
X1413319Y1105453D03*
X1426500Y1057500D03*
X1422500Y1091000D03*
X1429000D03*
X1406319Y1066831D03*
Y1056831D03*
X1350000Y1150000D03*
X1400000D03*
Y1200000D03*
X1350000D03*
X1366000Y1388000D03*
X1385474Y1429500D03*
X1380074D03*
X1383374Y1425000D03*
X1383674Y1419000D03*
X1406000Y1444000D03*
X1433500Y1490500D03*
X1428500Y1494000D03*
X1403500Y1513500D03*
X1398500D03*
X1363464Y1513685D03*
X1368464D03*
X1373464D03*
X1378464D03*
X1383464D03*
X1388464D03*
X1393464D03*
X1353464D03*
X1358464D03*
X1343464D03*
X1348464D03*
X1408464D03*
X1413464D03*
X1418464D03*
X1423464D03*
X1425890Y1510111D03*
Y1505111D03*
Y1500111D03*
X1527825Y68650D03*
X1514825D03*
X1474000Y78000D03*
X1508000Y36000D03*
X1468000Y42000D03*
X1482000Y66000D03*
X1528844Y6000D03*
X1523844D03*
X1518844D03*
X1513844D03*
X1508844D03*
X1503844D03*
X1498844D03*
X1493844D03*
X1488844D03*
X1483844D03*
X1478844D03*
X1473844D03*
X1468844D03*
X1463844D03*
X1458844D03*
X1453844D03*
X1448844D03*
X1443844D03*
X1438844D03*
X1530531Y66319D03*
Y81319D03*
X1526031Y93819D03*
Y84370D03*
X1439500Y81000D03*
X1530531Y51319D03*
X1508500Y102500D03*
X1441100Y130800D03*
X1494000Y98000D03*
X1484000Y158000D03*
X1530531Y151319D03*
X1526823Y161308D03*
X1437000Y185500D03*
X1438000Y150500D03*
X1530531Y121319D03*
Y131319D03*
X1526031Y103268D03*
X1515400Y119400D03*
X1523100Y193700D03*
X1502000Y196000D03*
X1457500Y289000D03*
X1508500Y292500D03*
X1450000Y350000D03*
X1462036Y379176D03*
X1484000Y432000D03*
X1465555Y400626D03*
X1472517Y400844D03*
X1527825Y521406D03*
X1514825D03*
X1442500Y532000D03*
X1480000Y546000D03*
X1510000Y488000D03*
X1476000Y518000D03*
X1526031Y546575D03*
Y556024D03*
Y537126D03*
X1530531Y534075D03*
Y519075D03*
Y504075D03*
X1451800Y583800D03*
X1498000Y586000D03*
X1490000Y598000D03*
X1500000Y640000D03*
X1460000Y646000D03*
X1530531Y614075D03*
X1437000Y638500D03*
X1530531Y604075D03*
Y584075D03*
Y574075D03*
X1515200Y572200D03*
X1438000Y603500D03*
X1508000Y748000D03*
X1472517Y853600D03*
X1465555Y853382D03*
X1462036Y831932D03*
X1442500Y984500D03*
X1478000Y976000D03*
X1480000Y1020000D03*
X1515400Y1025000D03*
X1530531Y1036831D03*
Y1026831D03*
Y956831D03*
X1526031Y1008780D03*
Y999331D03*
Y989882D03*
X1530531Y986831D03*
Y971831D03*
X1500000Y1100000D03*
X1530531Y1066831D03*
Y1056831D03*
X1437000Y1091000D03*
X1438000Y1056000D03*
X1450000Y1150000D03*
X1500000D03*
Y1200000D03*
X1450000D03*
X1500000Y1300000D03*
X1450000D03*
Y1350000D03*
X1500000D03*
Y1450000D03*
X1450000D03*
X1439716Y1490063D03*
X1444716D03*
X1449716D03*
X1454716D03*
X1459716D03*
X1464716D03*
X1469716D03*
X1474716D03*
X1479716D03*
X1484716D03*
X1489716D03*
X1494716D03*
X1499716D03*
X1504716D03*
X1509716D03*
X1514716D03*
X1519716D03*
X1524716D03*
X1529716D03*
X1594000Y56000D03*
X1574000Y26000D03*
X1608000Y62000D03*
Y50000D03*
X1623844Y6000D03*
X1618844D03*
X1613844D03*
X1608844D03*
X1603844D03*
X1598844D03*
X1593844D03*
X1588844D03*
X1583844D03*
X1578844D03*
X1573844D03*
X1568844D03*
X1563844D03*
X1558844D03*
X1553844D03*
X1548844D03*
X1543844D03*
X1538844D03*
X1533844D03*
X1549300Y56000D03*
X1548500Y62900D03*
X1553000Y35000D03*
X1556700Y45000D03*
X1537531Y27697D03*
X1593500Y160500D03*
X1546000Y112000D03*
X1547000Y156222D03*
Y185500D03*
X1562500Y150500D03*
X1561500Y185500D03*
X1553500Y189500D03*
X1598000Y206000D03*
X1568000Y204000D03*
X1592000Y236000D03*
X1550000Y350000D03*
X1586249Y379176D03*
X1553500Y431500D03*
X1604000Y432500D03*
X1596730Y400844D03*
X1589768Y400626D03*
X1566500Y533000D03*
X1604000Y536000D03*
X1594000Y506000D03*
X1558000Y482000D03*
X1559700Y511500D03*
X1556000Y501500D03*
X1548600Y534900D03*
X1552300Y522500D03*
X1537531Y480453D03*
X1570100Y583800D03*
X1568000Y660000D03*
X1584000Y648000D03*
X1553500Y638500D03*
X1561500Y639860D03*
X1537500Y656000D03*
X1551000Y605000D03*
X1562500Y603500D03*
X1602000Y684000D03*
X1566000Y772000D03*
X1550000Y850000D03*
X1596730Y853600D03*
X1589768Y853382D03*
X1586249Y831932D03*
X1599000Y941000D03*
X1579000Y940000D03*
X1564000Y876000D03*
X1537531Y933209D03*
X1604000Y1022000D03*
X1544000Y1004500D03*
X1566500Y985500D03*
X1600500Y975000D03*
X1612000Y980000D03*
X1548900Y987600D03*
X1556000Y954000D03*
X1559700Y964000D03*
X1552300Y975000D03*
X1561500Y1091000D03*
X1553500D03*
X1600000Y1100000D03*
X1537531Y1105453D03*
X1551000Y1057500D03*
X1547000Y1091000D03*
X1562500Y1056000D03*
X1600000Y1200000D03*
Y1150000D03*
X1550000Y1300000D03*
X1600000D03*
X1550000Y1350000D03*
X1600000D03*
Y1450000D03*
X1550000D03*
X1534716Y1490063D03*
X1539716D03*
X1544716D03*
X1549716D03*
X1554716D03*
X1559716D03*
X1564716D03*
X1569716D03*
X1574716D03*
X1579716D03*
X1584716D03*
X1589716D03*
X1594716D03*
X1599716D03*
X1604716D03*
X1609716D03*
X1614716D03*
X1619716D03*
X1624716D03*
X1652038Y68650D03*
X1639038D03*
X1718000Y66000D03*
X1680000Y26000D03*
X1632000D03*
X1718844Y6000D03*
X1713844D03*
X1708844D03*
X1703844D03*
X1698844D03*
X1693844D03*
X1688844D03*
X1683844D03*
X1678844D03*
X1673844D03*
X1668844D03*
X1663844D03*
X1658844D03*
X1653844D03*
X1648844D03*
X1643844D03*
X1638844D03*
X1633844D03*
X1628844D03*
X1676300Y69500D03*
X1683700Y58500D03*
X1686730Y80991D03*
X1654744Y66319D03*
Y81319D03*
X1650244Y93819D03*
Y84370D03*
X1680000Y48500D03*
X1654744Y51319D03*
X1661744Y27697D03*
X1636000Y176000D03*
X1677500Y185500D03*
X1686500Y150500D03*
X1675000Y152000D03*
X1654744Y151319D03*
Y161319D03*
X1685500Y185500D03*
X1654744Y121319D03*
X1653206Y134559D03*
X1650244Y103268D03*
X1639300Y119500D03*
X1648000Y212000D03*
X1682000Y206000D03*
X1661744Y199941D03*
X1671003Y190635D03*
X1650000Y380000D03*
X1638500Y311500D03*
X1715000Y305500D03*
X1648000Y468000D03*
X1714000Y391000D03*
X1652038Y521406D03*
X1639038D03*
X1682000Y484000D03*
X1720000Y506000D03*
X1650244Y546575D03*
Y556024D03*
Y537126D03*
X1654744Y534075D03*
Y519075D03*
Y504075D03*
X1661744Y480453D03*
X1680000Y501500D03*
X1673200Y535100D03*
X1683700Y511500D03*
X1676300Y522500D03*
X1706000Y646000D03*
X1632000Y648000D03*
X1634000Y618000D03*
X1661744Y652697D03*
X1654744Y614075D03*
X1671000Y638500D03*
X1685500D03*
X1677500D03*
X1654744Y604075D03*
Y584075D03*
X1652808Y574040D03*
X1686500Y603500D03*
X1675000Y605000D03*
X1638200Y572200D03*
X1700000Y700000D03*
X1650000D03*
Y750000D03*
X1700000D03*
X1650000Y850000D03*
X1720942Y853600D03*
X1713980Y853382D03*
X1710461Y831932D03*
X1690200Y937700D03*
X1718000Y938000D03*
X1716000Y878000D03*
X1661800Y933400D03*
X1668000Y1004000D03*
X1690500Y986000D03*
X1672800Y987300D03*
X1639100Y1024900D03*
X1654744Y1036831D03*
Y1026831D03*
Y956831D03*
X1676300Y975000D03*
X1683700Y964000D03*
X1680000Y954000D03*
X1650244Y1008780D03*
Y999331D03*
Y989882D03*
X1654744Y986831D03*
Y971831D03*
X1638000Y1082000D03*
X1696000Y1106000D03*
X1661744Y1105453D03*
X1677500Y1091000D03*
X1686500Y1056000D03*
X1671000Y1091000D03*
X1675000Y1057500D03*
X1685500Y1091000D03*
X1654744Y1066831D03*
Y1056831D03*
X1650000Y1150000D03*
X1700000D03*
Y1200000D03*
X1650000D03*
Y1300000D03*
X1674000Y1410000D03*
X1650000Y1350000D03*
X1669376Y1429200D03*
X1649500Y1497500D03*
X1646000Y1492000D03*
X1720968Y1513685D03*
X1715968D03*
X1710968D03*
X1705968D03*
X1700968D03*
X1695968D03*
X1690968D03*
X1685968D03*
X1680968D03*
X1670968D03*
X1675968D03*
X1629716Y1490063D03*
X1634716D03*
X1639716D03*
X1650488Y1504165D03*
Y1509165D03*
X1650968Y1513685D03*
X1655968D03*
X1660968D03*
X1665968D03*
X1694751Y1434000D03*
X1683926Y1453750D03*
X1672626Y1452500D03*
X1686226Y1432500D03*
X1776250Y68650D03*
X1763250D03*
X1756000Y25500D03*
X1730000Y58000D03*
X1813844Y6000D03*
X1808844D03*
X1803844D03*
X1798844D03*
X1793844D03*
X1788844D03*
X1783844D03*
X1778844D03*
X1773844D03*
X1768844D03*
X1763844D03*
X1758844D03*
X1753844D03*
X1748844D03*
X1743844D03*
X1738844D03*
X1733844D03*
X1728844D03*
X1723844D03*
X1778956Y66319D03*
Y81319D03*
X1774456Y93819D03*
Y84370D03*
X1785956Y27697D03*
X1778956Y51319D03*
X1730500Y177500D03*
X1730000Y136000D03*
X1746000Y106000D03*
X1809500Y185500D03*
X1801500D03*
X1811305Y147994D03*
X1799000Y152000D03*
X1795000Y185500D03*
X1778956Y151319D03*
Y161319D03*
Y121319D03*
Y131319D03*
X1774456Y103268D03*
X1763600Y119400D03*
X1804000Y205000D03*
X1724000Y232000D03*
X1754000Y234000D03*
X1750000Y200000D03*
X1785956Y199941D03*
X1768000Y310000D03*
X1781500Y366000D03*
X1801642Y379532D03*
X1724000Y422000D03*
X1745737Y400643D03*
X1759904Y400647D03*
X1812123Y401200D03*
X1805142Y400982D03*
X1814359Y473207D03*
X1749952Y405830D03*
X1776250Y521406D03*
X1763250D03*
X1813700Y548300D03*
X1796000Y566500D03*
X1728000Y554000D03*
X1757200Y558900D03*
X1730000Y568000D03*
X1774456Y556024D03*
X1767342Y533721D03*
X1774456Y546575D03*
X1785956Y480453D03*
X1804000Y501500D03*
X1807700Y511500D03*
X1800300Y522500D03*
X1798100Y537973D03*
X1785728Y538736D03*
X1778956Y519075D03*
Y504075D03*
X1818000Y656000D03*
X1762000Y628000D03*
X1756000Y646000D03*
X1785956Y652697D03*
X1795000Y638500D03*
X1801500D03*
X1809500D03*
X1778956Y614075D03*
X1810500Y603500D03*
X1799000Y605000D03*
X1778956Y604075D03*
Y584075D03*
Y574075D03*
X1759750Y576000D03*
X1758000Y748000D03*
X1756000Y684000D03*
X1808000Y848000D03*
X1760000Y846000D03*
X1800000Y800000D03*
X1778500Y917500D03*
X1738000Y904000D03*
X1785956Y933209D03*
X1794500Y1007000D03*
X1814500Y985500D03*
X1724000Y974000D03*
X1728000Y1002000D03*
X1796900Y987200D03*
X1763300Y1024800D03*
X1778956Y1036831D03*
Y1026831D03*
X1800300Y975000D03*
X1804000Y954000D03*
X1807700Y964000D03*
X1778956Y956831D03*
X1774456Y1008780D03*
Y999331D03*
Y989882D03*
X1778956Y986831D03*
Y971831D03*
X1730000Y1050000D03*
X1762000Y1080000D03*
X1785956Y1105453D03*
X1809500Y1091000D03*
X1801500D03*
X1810500Y1056000D03*
X1795000Y1091000D03*
X1799000Y1057500D03*
X1778956Y1066831D03*
Y1056831D03*
X1750000Y1150000D03*
Y1200000D03*
X1800000Y1300000D03*
Y1250000D03*
X1760000Y1394000D03*
X1800000Y1350000D03*
X1766526Y1429400D03*
X1760326Y1429500D03*
X1763926Y1419000D03*
X1763626Y1425000D03*
X1786004Y1513500D03*
X1780968Y1513685D03*
X1775968D03*
X1770968D03*
X1765968D03*
X1760968D03*
X1755968D03*
X1750968D03*
X1745968D03*
X1740968D03*
X1796004Y1513500D03*
X1801004D03*
X1806004D03*
X1811004D03*
X1816004D03*
X1730968Y1513685D03*
X1725968D03*
X1791004Y1513500D03*
X1735968Y1513685D03*
X1790226Y1458600D03*
X1803426Y1452600D03*
X1804326Y1480500D03*
X1794226Y1473300D03*
X1900463Y68650D03*
X1887463D03*
X1913844Y6000D03*
X1908844D03*
X1903844D03*
X1898844D03*
X1893844D03*
X1888844D03*
X1883844D03*
X1878844D03*
X1873844D03*
X1868844D03*
X1863844D03*
X1858844D03*
X1853844D03*
X1848844D03*
X1843844D03*
X1838844D03*
X1833844D03*
X1828844D03*
X1823844D03*
X1818844D03*
X1898669Y93819D03*
Y84370D03*
X1903169Y66319D03*
Y81319D03*
Y51319D03*
X1910169Y27697D03*
X1887900Y41300D03*
X1878000Y29300D03*
X1821850Y35400D03*
X1824200Y23400D03*
Y19000D03*
X1851500Y171500D03*
X1867600Y104300D03*
X1903169Y151319D03*
Y161319D03*
X1881000Y162200D03*
X1883000Y181500D03*
X1841000Y140000D03*
X1903169Y121319D03*
Y131319D03*
X1898669Y103268D03*
X1860817Y120141D03*
X1864800Y132500D03*
X1840500Y237500D03*
X1850000Y200000D03*
X1900000Y250000D03*
X1910169Y199941D03*
X1829500Y311000D03*
X1900000Y300000D03*
Y350000D03*
X1830000Y424000D03*
X1838000Y415500D03*
X1850000Y400000D03*
X1900000D03*
Y450000D03*
X1818359Y473207D03*
X1822359D03*
X1826359D03*
X1830359D03*
X1834359D03*
X1900463Y521406D03*
X1887463D03*
X1884000Y488000D03*
X1854000Y482000D03*
X1875000Y558000D03*
X1898669Y546575D03*
Y556024D03*
Y537126D03*
X1855750Y551000D03*
X1903169Y534075D03*
Y519075D03*
Y504075D03*
X1910169Y480453D03*
X1851400Y623800D03*
X1850000Y650000D03*
X1910169Y652697D03*
X1903169Y614075D03*
X1880500Y615200D03*
X1887000Y638500D03*
X1903169Y604075D03*
Y584075D03*
Y574075D03*
X1865000Y573000D03*
X1864700Y585500D03*
X1841000Y593000D03*
X1846000Y686000D03*
X1900000Y750000D03*
Y700000D03*
Y800000D03*
X1845155Y853600D03*
X1838193Y853382D03*
X1834674Y831932D03*
X1910169Y933209D03*
X1888763Y907525D03*
X1892763D03*
X1896763D03*
X1900763D03*
X1904763D03*
X1908763D03*
X1872500Y1010500D03*
X1826000Y1036500D03*
X1864500Y1038500D03*
X1865000Y1026000D03*
X1903169Y1036831D03*
Y1026831D03*
X1841000Y1046000D03*
X1903169Y956831D03*
X1898669Y1008780D03*
Y999331D03*
Y989882D03*
X1903169Y986831D03*
Y971831D03*
X1855750Y1004000D03*
X1850000Y1078000D03*
X1910169Y1105453D03*
X1887000Y1091500D03*
X1880500Y1068200D03*
X1903169Y1066831D03*
Y1056831D03*
X1850000Y1200000D03*
X1900000D03*
Y1150000D03*
X1850000D03*
X1900000Y1300000D03*
X1850000D03*
X1900000Y1250000D03*
X1850000D03*
X1900000Y1400000D03*
X1850000D03*
Y1350000D03*
X1900000D03*
X1904000Y1504000D03*
X1878000Y1484000D03*
X1822000Y1444000D03*
X1900000Y1450000D03*
X1869500Y1503500D03*
X1865500Y1500000D03*
X1829500Y1501500D03*
X1826500Y1506500D03*
X1855256Y1499118D03*
X1850256D03*
X1845256D03*
X1840256D03*
X1826040Y1513315D03*
X1821040D03*
X1835256Y1499118D03*
X1860256D03*
X1871157Y1509110D03*
X1871582Y1513685D03*
X1876582D03*
X1881582D03*
X1886582D03*
X1891582D03*
X1896582D03*
X1901582D03*
X1906582D03*
X1911582D03*
X1928843Y8985D03*
Y93985D03*
Y88985D03*
Y83985D03*
Y78985D03*
Y73985D03*
Y68985D03*
Y63985D03*
Y58985D03*
Y53985D03*
Y48985D03*
Y43985D03*
Y38985D03*
Y28985D03*
Y23985D03*
Y18985D03*
Y13985D03*
Y33985D03*
X1923844Y6000D03*
X1918844D03*
X1928843Y98985D03*
Y188985D03*
Y183985D03*
Y178985D03*
Y173985D03*
Y168985D03*
Y163985D03*
Y158985D03*
Y153985D03*
Y148985D03*
Y143985D03*
Y138985D03*
Y133985D03*
Y128985D03*
Y123985D03*
Y118985D03*
Y113985D03*
Y108985D03*
Y103985D03*
Y283985D03*
Y278985D03*
Y273985D03*
Y268985D03*
Y263985D03*
Y258985D03*
Y253985D03*
Y248985D03*
Y243985D03*
Y238985D03*
Y233985D03*
Y228985D03*
Y223985D03*
Y218985D03*
Y213985D03*
Y208985D03*
Y203985D03*
Y198985D03*
Y193985D03*
Y378985D03*
Y373985D03*
Y368985D03*
Y363985D03*
Y358985D03*
Y353985D03*
Y348985D03*
Y343985D03*
Y338985D03*
Y333985D03*
Y328985D03*
Y323985D03*
Y318985D03*
Y313985D03*
Y308985D03*
Y303985D03*
Y298985D03*
Y293985D03*
Y288985D03*
Y418985D03*
Y433985D03*
Y428985D03*
Y423985D03*
Y473985D03*
Y468985D03*
Y463985D03*
Y458985D03*
Y453985D03*
Y448985D03*
Y443985D03*
Y438985D03*
Y413985D03*
Y408985D03*
Y403985D03*
Y398985D03*
Y393985D03*
Y388985D03*
Y383985D03*
Y568985D03*
Y563985D03*
Y558985D03*
Y553985D03*
Y548985D03*
Y543985D03*
Y538985D03*
Y533985D03*
Y528985D03*
Y523985D03*
Y518985D03*
Y513985D03*
Y508985D03*
Y503985D03*
Y498985D03*
Y493985D03*
Y488985D03*
Y483985D03*
Y478985D03*
Y663985D03*
Y658985D03*
Y653985D03*
Y648985D03*
Y643985D03*
Y638985D03*
Y633985D03*
Y628985D03*
Y623985D03*
Y618985D03*
Y613985D03*
Y608985D03*
Y603985D03*
Y598985D03*
Y593985D03*
Y588985D03*
Y583985D03*
Y578985D03*
Y573985D03*
Y758985D03*
Y753985D03*
Y748985D03*
Y743985D03*
Y738985D03*
Y733985D03*
Y728985D03*
Y723985D03*
Y718985D03*
Y713985D03*
Y708985D03*
Y703985D03*
Y698985D03*
Y693985D03*
Y688985D03*
Y683985D03*
Y678985D03*
Y673985D03*
Y668985D03*
Y853985D03*
Y848985D03*
Y843985D03*
Y838985D03*
Y833985D03*
Y828985D03*
Y823985D03*
Y818985D03*
Y813985D03*
Y808985D03*
Y803985D03*
Y798985D03*
Y793985D03*
Y788985D03*
Y783985D03*
Y778985D03*
Y773985D03*
Y768985D03*
Y763985D03*
Y918985D03*
Y913985D03*
Y908985D03*
Y903985D03*
Y898985D03*
Y893985D03*
Y888985D03*
Y883985D03*
Y878985D03*
Y873985D03*
Y868985D03*
Y863985D03*
Y858985D03*
Y948985D03*
Y943985D03*
Y938985D03*
Y933985D03*
Y928985D03*
Y923985D03*
Y1043985D03*
Y1038985D03*
Y1033985D03*
Y1028985D03*
Y1023985D03*
Y1018985D03*
Y1013985D03*
Y1008985D03*
Y1003985D03*
Y998985D03*
Y993985D03*
Y988985D03*
Y983985D03*
Y978985D03*
Y973985D03*
Y968985D03*
Y963985D03*
Y958985D03*
Y953985D03*
Y1143985D03*
Y1138985D03*
Y1133985D03*
Y1128985D03*
Y1123985D03*
Y1118985D03*
Y1113985D03*
Y1108985D03*
Y1103985D03*
Y1098985D03*
Y1093985D03*
Y1088985D03*
Y1083985D03*
Y1078985D03*
Y1073985D03*
Y1068985D03*
Y1063985D03*
Y1058985D03*
Y1053985D03*
Y1048985D03*
Y1238985D03*
Y1233985D03*
Y1228985D03*
Y1223985D03*
Y1218985D03*
Y1213985D03*
Y1208985D03*
Y1203985D03*
Y1198985D03*
Y1193985D03*
Y1188985D03*
Y1183985D03*
Y1178985D03*
Y1173985D03*
Y1168985D03*
Y1163985D03*
Y1158985D03*
Y1153985D03*
Y1148985D03*
Y1288985D03*
Y1293985D03*
Y1298985D03*
Y1303985D03*
Y1308985D03*
Y1313985D03*
Y1318985D03*
Y1323985D03*
Y1328985D03*
Y1333985D03*
Y1283985D03*
Y1278985D03*
Y1273985D03*
Y1268985D03*
Y1263985D03*
Y1258985D03*
Y1253985D03*
Y1248985D03*
Y1243985D03*
Y1348985D03*
Y1353985D03*
Y1358985D03*
Y1363985D03*
Y1368985D03*
Y1373985D03*
Y1378985D03*
Y1383985D03*
Y1388985D03*
Y1393985D03*
Y1398985D03*
Y1403985D03*
Y1408985D03*
Y1413985D03*
Y1418985D03*
Y1423985D03*
Y1428985D03*
Y1338985D03*
Y1343985D03*
Y1448985D03*
Y1443985D03*
Y1433985D03*
Y1438985D03*
X1920000Y1458000D03*
X1917500Y1463500D03*
X1916582Y1513685D03*
X1917031Y1509134D03*
Y1504134D03*
Y1499134D03*
Y1494134D03*
Y1489134D03*
Y1484134D03*
Y1479134D03*
Y1474134D03*
Y1469134D03*
X1926500Y1455000D03*
G54D27*
X159860Y924548D03*
X163860D03*
X257687Y487212D03*
X261687D03*
X1800556Y490630D03*
X1804556D03*
X1874660Y925148D03*
X1878660D03*
G54D14*
X91114Y909791D03*
X85000Y885500D03*
X89000D03*
Y881500D03*
X85000D03*
X89000Y877500D03*
X85000D03*
X89000Y889500D03*
X85000D03*
X89000Y893500D03*
X85000D03*
X81166Y892754D03*
Y888754D03*
X41263Y887025D03*
X48763D03*
X55763D03*
X51263Y894525D03*
X46763Y891525D03*
X178993Y455018D03*
Y451018D03*
X182827Y447764D03*
Y455764D03*
X186827D03*
X182827Y451764D03*
X186827D03*
X182827Y439764D03*
Y443764D03*
X188941Y472055D03*
X153590Y449289D03*
X146590D03*
X149090Y456789D03*
X144590Y453789D03*
X139090Y449289D03*
X168863Y916425D03*
Y920425D03*
X154663Y916425D03*
Y920425D03*
X266690Y479089D03*
Y483089D03*
X252490D03*
Y479089D03*
X666100Y1360800D03*
Y1368700D03*
Y1376600D03*
Y1352900D03*
X658200Y1360800D03*
Y1368700D03*
Y1376600D03*
Y1352900D03*
X666100Y1345000D03*
X658200D03*
X705600Y1360800D03*
Y1352900D03*
Y1345000D03*
Y1376600D03*
Y1368700D03*
X699600Y1408200D03*
Y1392400D03*
Y1400300D03*
X697700Y1345000D03*
Y1360800D03*
Y1368700D03*
Y1376600D03*
X697100Y1384600D03*
X697700Y1352900D03*
X691700Y1408200D03*
Y1400300D03*
X675900D03*
X683800D03*
Y1408200D03*
X675900D03*
X689800Y1352900D03*
Y1384500D03*
Y1376600D03*
X691700Y1392400D03*
X689800Y1368700D03*
Y1360800D03*
X674000D03*
X681900D03*
Y1368700D03*
X674000D03*
X675900Y1392400D03*
X683800D03*
X674000Y1376600D03*
X681900D03*
Y1384500D03*
X674000D03*
Y1352900D03*
X681900D03*
X689800Y1345000D03*
X681900D03*
X674000D03*
X1721762Y458436D03*
Y454436D03*
X1696359Y452707D03*
X1689359D03*
X1691859Y460207D03*
X1687359Y457207D03*
X1681859Y452707D03*
X1725596Y447182D03*
X1729596Y443182D03*
X1725596D03*
X1729596Y455182D03*
X1725596D03*
X1729596Y459182D03*
X1725596D03*
Y451182D03*
X1729596Y447182D03*
Y451182D03*
X1731710Y475473D03*
X1809559Y482507D03*
Y486507D03*
X1795359D03*
Y482507D03*
X1796166Y892754D03*
Y888754D03*
X1804000Y885500D03*
Y881500D03*
X1800000Y885500D03*
Y893500D03*
X1804000D03*
X1800000Y889500D03*
X1804000D03*
X1800000Y877500D03*
X1804000D03*
X1800000Y881500D03*
X1806114Y909791D03*
X1770763Y887025D03*
X1763763D03*
X1766263Y894525D03*
X1761763Y891525D03*
X1756263Y887025D03*
X1883663Y917025D03*
Y921025D03*
X1869463D03*
Y917025D03*
G54D28*
X184252Y1445275D03*
Y1466929D03*
X167716Y1445275D03*
Y1466929D03*
X217322Y1445275D03*
Y1466929D03*
X200787Y1445275D03*
Y1466929D03*
X581102Y1445275D03*
Y1466929D03*
X564567Y1445275D03*
Y1466929D03*
X548031Y1445275D03*
Y1466929D03*
X597637Y1445275D03*
Y1466929D03*
X1331496Y1445275D03*
Y1466929D03*
X1314960Y1445275D03*
Y1466929D03*
X1364566Y1445275D03*
Y1466929D03*
X1348031Y1445275D03*
Y1466929D03*
X1711811Y1445275D03*
Y1466929D03*
X1695275Y1445275D03*
Y1466929D03*
X1744881Y1445275D03*
Y1466929D03*
X1728346Y1445275D03*
Y1466929D03*
G54D10*
X59400Y32600D03*
X63374Y1454500D03*
X390757Y1511515D03*
X812347Y17406D03*
X885639Y1511515D03*
X1187163Y158305D03*
X1538001Y1511515D03*
X1869500Y1461500D03*
G54D21*
X173228Y55118D03*
X421653Y94488D03*
X670078Y55118D03*
X1343701D03*
X1592126Y94488D03*
X1840551Y55118D03*
G54D33*
X503248Y715748D03*
X1673917Y262992D03*
G54D30*
X246535Y1320472D03*
X531535D03*
G54D31*
X266535D03*
X511535D03*
G54D29*
X167716Y1495669D03*
X233858D03*
X548031D03*
X614173D03*
X1314960D03*
X1381102D03*
X1695275D03*
X1761417D03*
G54D23*
X173228Y122047D03*
X670079D03*
X1343701Y122046D03*
X1840551D03*
G54D37*
X1104528Y1162257D03*
G54D13*
X69942Y406555D03*
X57675Y851609D03*
X180400Y852300D03*
X202500Y82500D03*
X204075Y398609D03*
X305775Y398909D03*
Y851609D03*
X369086Y1313208D03*
X374086D03*
X379086D03*
X384086D03*
X324086D03*
X329086D03*
X334086D03*
X339086D03*
X344086D03*
X349086D03*
X354086D03*
X359086D03*
X364086D03*
X294086D03*
X299086D03*
X304086D03*
X309086D03*
X319086D03*
X430275Y399351D03*
X429975Y851409D03*
X389086Y1313208D03*
X394086D03*
X554475Y399651D03*
X524236Y1463672D03*
X665475Y399378D03*
X670875Y851409D03*
X594055Y852609D03*
X658200Y1329200D03*
X666100D03*
Y1337100D03*
X658200D03*
X699500Y82500D03*
X705600Y1329200D03*
X697700Y1321300D03*
Y1329200D03*
X689800D03*
Y1321300D03*
X693800Y1313900D03*
Y1306000D03*
X685900D03*
X678000D03*
Y1313900D03*
X685900D03*
X681900Y1321300D03*
X674000D03*
Y1329200D03*
X681900D03*
X693800Y1298000D03*
X685900D03*
X678000D03*
X705600Y1337100D03*
X697700D03*
X689800D03*
X681900D03*
X674000D03*
X826843Y409096D03*
Y404296D03*
Y399496D03*
X822043D03*
Y404296D03*
Y409096D03*
X807643Y408996D03*
Y404196D03*
Y399396D03*
X802843D03*
Y404196D03*
Y408996D03*
X822400Y567100D03*
Y562300D03*
Y557500D03*
X817600D03*
Y562300D03*
Y567100D03*
X803200Y557400D03*
Y562200D03*
Y567000D03*
X798400Y557400D03*
Y562200D03*
Y567000D03*
X853900Y839200D03*
X834470Y944430D03*
X842270Y942411D03*
X796301Y959795D03*
X808300Y1197300D03*
X813100D03*
Y1206900D03*
Y1202100D03*
X808300D03*
Y1206900D03*
X794100Y1197300D03*
X789300D03*
X794100Y1202100D03*
Y1206900D03*
X789300Y1202100D03*
Y1206900D03*
X957500Y842400D03*
X944000D03*
X944500Y1134500D03*
X952500D03*
X974015Y284449D03*
X986614D03*
X974015Y278544D03*
X986614D03*
X974015Y307087D03*
X986614D03*
X1002362D03*
X1014960D03*
X1030709D03*
X1043307D03*
X974015Y312993D03*
X1002362D03*
X1030709D03*
X974015Y301182D03*
X1002362D03*
X1030709D03*
X974015Y290355D03*
X986614Y312993D03*
X1014960D03*
X1043307D03*
X986614Y301182D03*
X1014960D03*
X1043307D03*
X986614Y290355D03*
X1038200Y762300D03*
X1021194Y766883D03*
X1035594Y766983D03*
X1040394D03*
X1021194Y771683D03*
Y776483D03*
X1035594Y776583D03*
Y771783D03*
X1040394D03*
Y776583D03*
X1016394Y766883D03*
Y776483D03*
Y771683D03*
X962000Y842400D03*
X997083Y895935D03*
X986728Y891100D03*
X960500Y1134500D03*
X1065055Y226895D03*
Y231895D03*
Y236895D03*
Y241895D03*
Y221895D03*
X1119877Y408072D03*
Y403272D03*
Y398472D03*
X1124677D03*
Y403272D03*
Y408072D03*
X1100677Y407972D03*
Y403172D03*
Y398372D03*
X1105477D03*
Y403172D03*
Y407972D03*
X1128700Y1206500D03*
X1133500D03*
Y1201700D03*
X1128700D03*
X1133500Y1196900D03*
X1128700D03*
X1109600Y1197100D03*
X1114400D03*
X1109600Y1201900D03*
X1114400D03*
Y1206700D03*
X1109600D03*
X1124612Y1388773D03*
X1130112Y1363273D03*
X1138112D03*
X1132112Y1380773D03*
X1114112Y1363273D03*
X1118112D03*
X1126112D03*
X1110512Y1403273D03*
X1229000Y189500D03*
X1225000Y194000D03*
X1228344Y852351D03*
X1178712Y1372573D03*
X1200962Y1413023D03*
X1209819Y1417377D03*
X1252750Y53650D03*
X1265250D03*
X1274396Y407915D03*
X1252750Y506406D03*
X1265250D03*
X1376963Y53650D03*
X1389463D03*
X1352557Y399595D03*
X1376963Y506406D03*
X1389463D03*
X1352557Y852351D03*
X1501175Y53650D03*
X1513675D03*
X1476769Y399595D03*
X1501175Y506406D03*
X1513675D03*
X1476769Y852351D03*
X1625388Y53650D03*
X1600982Y399595D03*
X1625388Y506406D03*
X1597000Y857500D03*
X1637888Y53650D03*
Y506406D03*
X1749600Y53650D03*
X1762100D03*
X1811700Y59550D03*
X1764168Y405501D03*
X1816375Y399951D03*
X1749600Y506406D03*
X1762100D03*
X1725194Y852351D03*
X1873813Y53650D03*
X1886313D03*
X1820200Y70140D03*
X1885200Y81000D03*
X1871400Y82000D03*
X1873813Y506406D03*
X1886313D03*
X1883200Y534600D03*
X1849407Y852351D03*
X1883100Y984750D03*
G54D17*
X127988Y67319D03*
Y80319D03*
X148050Y20971D03*
X126900Y39500D03*
X150700Y33100D03*
X127988Y520075D03*
Y533075D03*
Y972831D03*
Y985831D03*
X252200Y67319D03*
Y80319D03*
Y520075D03*
Y533075D03*
Y972831D03*
Y985831D03*
X376413Y67319D03*
Y80319D03*
Y520075D03*
Y533075D03*
Y972831D03*
Y985831D03*
X373492Y1317441D03*
Y1322441D03*
Y1327441D03*
Y1332441D03*
X343688Y1317736D03*
Y1322736D03*
Y1327736D03*
Y1332736D03*
X313688D03*
Y1327736D03*
Y1322736D03*
Y1317736D03*
Y1312736D03*
X373492Y1337441D03*
Y1342441D03*
Y1347441D03*
Y1352441D03*
X343688Y1337736D03*
Y1342736D03*
Y1347736D03*
Y1352736D03*
X313688D03*
Y1347736D03*
Y1342736D03*
Y1337736D03*
X500625Y67319D03*
Y80319D03*
Y520075D03*
Y533075D03*
Y972831D03*
Y985831D03*
X505224Y1424156D03*
X624838Y67319D03*
Y80319D03*
Y520075D03*
Y533075D03*
Y972831D03*
Y985831D03*
X749051Y67319D03*
Y80319D03*
Y520075D03*
Y533075D03*
Y972831D03*
Y985831D03*
X855100Y258531D03*
X841000D03*
X826700D03*
X869300D03*
X878740Y655190D03*
Y647190D03*
X932986Y752682D03*
X876255Y818998D03*
X880983Y804420D03*
X936543Y762518D03*
X988341Y563811D03*
X985631Y559671D03*
X984197Y533383D03*
X966861Y772518D03*
X982500Y1217000D03*
Y1209000D03*
X1033287Y1410500D03*
X1091089Y520057D03*
X1105262D03*
X1119435D03*
X1133609D03*
X1095026Y527143D03*
X1109199D03*
X1123372D03*
X1091089Y534230D03*
X1105262D03*
X1119435D03*
X1133609D03*
X1095026Y541317D03*
X1109199D03*
X1123372D03*
X1091089Y548403D03*
X1105262D03*
X1119435D03*
X1133609D03*
X1095026Y555490D03*
X1109199D03*
X1123372D03*
X1091089Y562576D03*
X1105262D03*
X1119435D03*
X1133609D03*
X1095026Y569663D03*
X1109199D03*
X1123372D03*
X1091089Y691711D03*
Y705884D03*
Y720057D03*
Y734230D03*
Y748403D03*
Y762577D03*
X1105262Y691711D03*
Y705884D03*
Y720057D03*
Y734230D03*
Y748403D03*
Y762577D03*
X1119435Y691711D03*
Y705884D03*
Y720057D03*
Y734230D03*
Y748403D03*
Y762577D03*
X1133609Y691711D03*
Y705884D03*
Y720057D03*
Y734230D03*
Y748403D03*
Y762577D03*
X1095026Y698797D03*
Y712970D03*
Y727144D03*
Y741317D03*
Y755490D03*
X1109199Y698797D03*
Y712970D03*
Y727144D03*
Y741317D03*
Y755490D03*
X1123372Y698797D03*
Y712970D03*
Y727144D03*
Y741317D03*
Y755490D03*
X1091089Y776750D03*
Y790923D03*
Y805096D03*
Y819270D03*
Y833443D03*
Y847616D03*
X1105262Y776750D03*
Y790923D03*
Y805096D03*
Y819270D03*
Y833443D03*
Y847616D03*
X1119435Y776750D03*
Y790923D03*
Y805096D03*
Y819270D03*
Y833443D03*
Y847616D03*
X1133609Y776750D03*
Y790923D03*
Y805096D03*
Y819270D03*
Y833443D03*
Y847616D03*
X1095026Y769663D03*
Y783836D03*
Y798010D03*
Y812183D03*
Y826356D03*
Y840529D03*
Y854703D03*
X1109199Y769663D03*
Y783836D03*
Y798010D03*
Y812183D03*
Y826356D03*
Y840529D03*
Y854703D03*
X1123372Y769663D03*
Y783836D03*
Y798010D03*
Y812183D03*
Y826356D03*
Y840529D03*
Y854703D03*
X1091089Y861789D03*
Y875962D03*
Y890136D03*
Y904309D03*
Y918482D03*
Y932655D03*
X1105262Y861789D03*
Y875962D03*
Y890136D03*
Y904309D03*
Y918482D03*
Y932655D03*
X1119435Y861789D03*
Y875962D03*
Y890136D03*
Y904309D03*
Y918482D03*
Y932655D03*
X1133609Y861789D03*
Y875962D03*
Y890136D03*
Y904309D03*
Y918482D03*
Y932655D03*
X1095026Y868876D03*
Y883049D03*
Y897222D03*
Y911396D03*
Y925569D03*
Y939742D03*
X1109199Y868876D03*
Y883049D03*
Y897222D03*
Y911396D03*
Y925569D03*
Y939742D03*
X1123372Y868876D03*
Y883049D03*
Y897222D03*
Y911396D03*
Y925569D03*
Y939742D03*
X1101405Y1120040D03*
X1119633D03*
X1108098D03*
X1126326D03*
X1130873Y1490848D03*
Y1495848D03*
X1223730Y1285803D03*
X1230600D03*
X1235600D03*
X1202394D03*
X1197394D03*
X1190524D03*
X1273975Y972831D03*
Y985831D03*
X1398188Y972831D03*
Y985831D03*
X1522400Y972831D03*
Y985831D03*
X1646613Y972831D03*
Y985831D03*
X1808600Y78200D03*
X1803500Y82200D03*
X1795600Y44900D03*
X1817500Y32700D03*
X1814850Y21500D03*
X1770825Y972831D03*
Y985831D03*
X1866700Y512800D03*
X1866500Y507250D03*
X1859300Y524500D03*
X1895038Y972831D03*
Y985831D03*
X1859600Y960250D03*
X1870800Y973100D03*
X1859300Y977500D03*
G54D25*
X168937Y850845D03*
X154737Y854845D03*
Y850845D03*
X168937Y854845D03*
X266764Y417509D03*
Y413509D03*
X252564D03*
Y417509D03*
X581800Y1321200D03*
Y1329100D03*
X589700D03*
Y1321200D03*
X594800Y1313500D03*
X597600Y1321200D03*
Y1329100D03*
X610600Y1313500D03*
Y1305600D03*
Y1297600D03*
X602700Y1313500D03*
Y1305600D03*
Y1297600D03*
X629200Y1329100D03*
X605500Y1321200D03*
X613400D03*
X605500Y1329100D03*
X613400D03*
X621300D03*
X581800Y1337000D03*
X589700D03*
X597600D03*
X629200D03*
X613400D03*
X621300D03*
X605500D03*
X944200Y1083100D03*
X938900Y1103700D03*
X938800Y1109300D03*
X1032361Y1114039D03*
X1021970Y1096850D03*
X982500Y1136500D03*
X986500Y1131500D03*
X982500Y1144500D03*
X1809633Y420927D03*
Y416927D03*
X1795433D03*
Y420927D03*
X1883737Y855445D03*
Y851445D03*
X1869537D03*
Y855445D03*
G54D26*
X163740Y846722D03*
X159740D03*
X257567Y409386D03*
X261567D03*
X1800436Y412804D03*
X1804436D03*
X1874540Y847322D03*
X1878540D03*
G36*
G01X149667Y265962D02*
G02X112734I-18466J-14781D01*
G03X119307Y278426I-29176J23351D01*
G02X143094I11894J-3623D01*
G03X149667Y265962I35749J10887D01*
G37*
G36*
G01Y718718D02*
G02X112734I-18466J-14781D01*
G03X119307Y731182I-29176J23351D01*
G02X143094I11894J-3623D01*
G03X149667Y718718I35749J10887D01*
G37*
G36*
G01Y1171473D02*
G02X112734I-18466J-14781D01*
G03X119307Y1183937I-29176J23351D01*
G02X143094I11894J-3623D01*
G03X149667Y1171473I35749J10887D01*
G37*
G36*
G01X397699Y265962D02*
G02X360766I-18467J-14781D01*
G03X367339Y278426I-29176J23351D01*
G02X391126I11894J-3623D01*
G03X397699Y265962I35749J10887D01*
G37*
G36*
G01Y718718D02*
G02X360766I-18467J-14781D01*
G03X367339Y731182I-29176J23351D01*
G02X391126I11894J-3623D01*
G03X397699Y718718I35749J10887D01*
G37*
G36*
G01Y1171473D02*
G02X360766I-18467J-14781D01*
G03X367339Y1183937I-29176J23351D01*
G02X391126I11894J-3623D01*
G03X397699Y1171473I35749J10887D01*
G37*
G36*
G01X645730Y265962D02*
G02X608797I-18466J-14781D01*
G03X615370Y278426I-29176J23351D01*
G02X639157I11893J-3623D01*
G03X645730Y265962I35749J10887D01*
G37*
G36*
G01Y718718D02*
G02X608797I-18466J-14781D01*
G03X615370Y731182I-29176J23351D01*
G02X639157I11893J-3623D01*
G03X645730Y718718I35749J10887D01*
G37*
G36*
G01Y1171473D02*
G02X608797I-18466J-14781D01*
G03X615370Y1183937I-29176J23351D01*
G02X639157I11893J-3623D01*
G03X645730Y1171473I35749J10887D01*
G37*
G36*
G01X765711Y384859D02*
G02X728778I-18466J-14781D01*
G03X735351Y397323I-29176J23351D01*
G02X759138I11893J-3623D01*
G03X765711Y384859I35749J10887D01*
G37*
G36*
G01Y817930D02*
G02X728778I-18466J-14781D01*
G03X735351Y830394I-29176J23351D01*
G02X759138I11893J-3623D01*
G03X765711Y817930I35749J10887D01*
G37*
G36*
G01X979884Y706906D02*
G02X942951I-18467J-14781D01*
G03X949524Y719370I-29176J23351D01*
G02X973311I11894J-3623D01*
G03X979884Y706906I35749J10887D01*
G37*
G36*
G01Y975410D02*
G02X942951I-18467J-14781D01*
G03X949524Y987874I-29176J23351D01*
G02X973311I11894J-3623D01*
G03X979884Y975410I35749J10887D01*
G37*
G36*
G01X1200356Y384859D02*
G02X1163423I-18467J-14781D01*
G03X1169996Y397323I-29176J23351D01*
G02X1193783I11894J-3623D01*
G03X1200356Y384859I35749J10887D01*
G37*
G36*
G01Y975410D02*
G02X1163423I-18467J-14781D01*
G03X1169996Y987874I-29176J23351D01*
G02X1193783I11894J-3623D01*
G03X1200356Y975410I35749J10887D01*
G37*
G36*
G01X1320337Y265961D02*
G02X1283404I-18467J-14781D01*
G03X1289977Y278425I-29176J23351D01*
G02X1313764I11894J-3623D01*
G03X1320337Y265961I35749J10887D01*
G37*
G36*
G01Y718718D02*
G02X1283404I-18467J-14781D01*
G03X1289977Y731182I-29176J23351D01*
G02X1313764I11894J-3623D01*
G03X1320337Y718718I35749J10887D01*
G37*
G36*
G01Y1171473D02*
G02X1283404I-18467J-14781D01*
G03X1289977Y1183937I-29176J23351D01*
G02X1313764I11894J-3623D01*
G03X1320337Y1171473I35749J10887D01*
G37*
G36*
G01X1568368Y265962D02*
G02X1531435I-18467J-14781D01*
G03X1538008Y278426I-29176J23351D01*
G02X1561795I11894J-3623D01*
G03X1568368Y265962I35749J10887D01*
G37*
G36*
G01Y718718D02*
G02X1531435I-18467J-14781D01*
G03X1538008Y731182I-29176J23351D01*
G02X1561795I11894J-3623D01*
G03X1568368Y718718I35749J10887D01*
G37*
G36*
G01Y1171473D02*
G02X1531435I-18467J-14781D01*
G03X1538008Y1183937I-29176J23351D01*
G02X1561795I11894J-3623D01*
G03X1568368Y1171473I35749J10887D01*
G37*
G36*
G01X1816400Y265961D02*
G02X1779467I-18466J-14781D01*
G03X1786040Y278425I-29176J23351D01*
G02X1809827I11894J-3623D01*
G03X1816400Y265961I35749J10887D01*
G37*
G36*
G01Y718718D02*
G02X1779467I-18466J-14781D01*
G03X1786040Y731182I-29176J23351D01*
G02X1809827I11894J-3623D01*
G03X1816400Y718718I35749J10887D01*
G37*
G36*
G01Y1171473D02*
G02X1779467I-18466J-14781D01*
G03X1786040Y1183937I-29176J23351D01*
G02X1809827I11894J-3623D01*
G03X1816400Y1171473I35749J10887D01*
G37*
%LPC*%
G75*
G54D38*
G01X466941Y-145664D02*
Y-225664D01*
G01D02*
X1593241D01*
G01X462941Y-129664D02*
G02I-12000J0D01*
G01X457791D02*
G02I-6850J0D01*
G01X450941Y-145664D02*
Y-113664D01*
G01X466941Y-129664D02*
X434941D01*
G01X466941Y-145664D02*
X1593241D01*
G01X466941Y-181164D02*
X1593241D01*
G01X805741Y-145664D02*
Y-225664D01*
G01X943241Y-145664D02*
Y-225664D01*
G01X1058241Y-145664D02*
Y-225664D01*
G01X1225741Y-145664D02*
Y-225664D01*
G01X1395741Y-145664D02*
Y-225664D01*
G01X1593241Y-145664D02*
Y-225664D01*
G01X1621241Y-129664D02*
G02I-12000J0D01*
G01X1616091D02*
G02I-6850J0D01*
G01X1609241Y-145664D02*
Y-113664D01*
G01X1625241Y-129664D02*
X1593241D01*
G54D39*
G01X489037Y-206331D02*
X489911Y-205456D01*
X490566Y-203998D01*
X491003Y-201955D01*
X490566Y-200206D01*
X489693Y-199039D01*
X488164Y-198164D01*
X482269D01*
Y-215664D01*
X489474D01*
X491003Y-214498D01*
X491876Y-212747D01*
X492313Y-210706D01*
X491876Y-208664D01*
X490566Y-206914D01*
X489037Y-206331D01*
X482269D01*
G01X501734Y-215664D02*
Y-203998D01*
G01Y-206331D02*
X502826Y-205164D01*
X503918Y-204289D01*
X505446Y-203998D01*
X506537Y-204289D01*
X507848Y-205164D01*
G01X517706Y-220914D02*
X519016Y-221497D01*
X520763Y-220914D01*
X521854Y-219748D01*
X522728Y-218289D01*
X524037Y-213623D01*
X526876Y-203998D01*
G01X519889D02*
X524037Y-213623D01*
G01X543284Y-205456D02*
X541756Y-204289D01*
X540446Y-203998D01*
X538699Y-204581D01*
X537389Y-205747D01*
X536516Y-207789D01*
X536297Y-209831D01*
X536516Y-211873D01*
X537389Y-213623D01*
X538699Y-215081D01*
X540446Y-215664D01*
X541974Y-215081D01*
X543284Y-213914D01*
G01X554016Y-207789D02*
X561003D01*
X560348Y-205747D01*
X559256Y-204581D01*
X557728Y-203998D01*
X556199Y-204289D01*
X554889Y-205164D01*
X554016Y-207206D01*
X553579Y-208956D01*
Y-210706D01*
X554016Y-212456D01*
X555108Y-214206D01*
X556418Y-215372D01*
X557946Y-215664D01*
X559474Y-215081D01*
X561003Y-213331D01*
G01X597094Y-199623D02*
X595784Y-198747D01*
X594256Y-198164D01*
X592509D01*
X590544Y-199039D01*
X589016Y-200497D01*
X587924Y-202248D01*
X587051Y-205164D01*
X586832Y-207789D01*
X587269Y-210414D01*
X587924Y-212164D01*
X589234Y-213914D01*
X590763Y-215081D01*
X592291Y-215664D01*
X593819D01*
X595348Y-215081D01*
X596658Y-214206D01*
X597750Y-213040D01*
G01X613721Y-215664D02*
Y-203998D01*
G01Y-206039D02*
X612848Y-204873D01*
X611537Y-204289D01*
X610009Y-203998D01*
X608481Y-204581D01*
X607171Y-205747D01*
X606297Y-207497D01*
X605861Y-209831D01*
X606297Y-212164D01*
X607171Y-213914D01*
X608481Y-215081D01*
X610009Y-215664D01*
X611537Y-215372D01*
X612848Y-214498D01*
X613721Y-213331D01*
G01X623579Y-215664D02*
Y-203998D01*
G01Y-206914D02*
X624453Y-205456D01*
X625763Y-204289D01*
X627509Y-203998D01*
X629037Y-204289D01*
X630348Y-205456D01*
X631003Y-207497D01*
Y-215664D01*
G01X640206Y-220914D02*
X641516Y-221497D01*
X643263Y-220914D01*
X644354Y-219748D01*
X645228Y-218289D01*
X646537Y-213623D01*
X649376Y-203998D01*
G01X642389D02*
X646537Y-213623D01*
G01X662291Y-215664D02*
X660981Y-215372D01*
X659671Y-214206D01*
X658797Y-212164D01*
X658361Y-209831D01*
X658797Y-207497D01*
X659671Y-205456D01*
X660981Y-204289D01*
X662291Y-203998D01*
X663601Y-204289D01*
X664911Y-205456D01*
X665784Y-207497D01*
X666003Y-209831D01*
X665784Y-212164D01*
X664911Y-214206D01*
X663601Y-215372D01*
X662291Y-215664D01*
G01X676079D02*
Y-203998D01*
G01Y-206914D02*
X676953Y-205456D01*
X678263Y-204289D01*
X680009Y-203998D01*
X681537Y-204289D01*
X682848Y-205456D01*
X683503Y-207497D01*
Y-215664D01*
G01X710424D02*
Y-198164D01*
X715883D01*
X717629Y-199039D01*
X718721Y-200206D01*
X719158Y-202539D01*
X718721Y-204873D01*
X717411Y-206331D01*
X715883Y-207206D01*
X710424D01*
G01X715883D02*
X719158Y-215664D01*
G01X732291Y-216247D02*
X731854Y-215956D01*
Y-215372D01*
X732291Y-215081D01*
X732728Y-215372D01*
Y-215956D01*
X732291Y-216247D01*
G01X744988Y-215664D02*
Y-198164D01*
X749354D01*
X751101Y-199039D01*
X752411Y-200206D01*
X753503Y-201955D01*
X754376Y-203998D01*
X754594Y-206914D01*
X754376Y-209831D01*
X753503Y-211873D01*
X752411Y-213623D01*
X751101Y-214789D01*
X749354Y-215664D01*
X744988D01*
G01X762924D02*
Y-198164D01*
X768164D01*
X769911Y-199039D01*
X771221Y-201081D01*
X771658Y-203414D01*
X771221Y-205747D01*
X770129Y-207497D01*
X768164Y-208373D01*
X762924D01*
G01X786537Y-206331D02*
X787411Y-205456D01*
X788066Y-203998D01*
X788503Y-201955D01*
X788066Y-200206D01*
X787193Y-199039D01*
X785664Y-198164D01*
X779769D01*
Y-215664D01*
X786974D01*
X788503Y-214498D01*
X789376Y-212747D01*
X789813Y-210706D01*
X789376Y-208664D01*
X788066Y-206914D01*
X786537Y-206331D01*
X779769D01*
G01X595364Y-170664D02*
Y-153164D01*
X601041Y-167747D01*
X606718Y-153164D01*
Y-170664D01*
G01X618541D02*
X617231Y-170372D01*
X615921Y-169206D01*
X615047Y-167164D01*
X614611Y-164831D01*
X615047Y-162497D01*
X615921Y-160456D01*
X617231Y-159289D01*
X618541Y-158998D01*
X619851Y-159289D01*
X621161Y-160456D01*
X622034Y-162497D01*
X622253Y-164831D01*
X622034Y-167164D01*
X621161Y-169206D01*
X619851Y-170372D01*
X618541Y-170664D01*
G01X639971Y-153164D02*
Y-170664D01*
G01Y-168040D02*
X639098Y-169498D01*
X637787Y-170372D01*
X636259Y-170664D01*
X634513Y-170081D01*
X633203Y-168623D01*
X632329Y-166873D01*
X632111Y-164831D01*
X632329Y-162789D01*
X633203Y-161039D01*
X634513Y-159581D01*
X636259Y-158998D01*
X637787Y-159289D01*
X638879Y-159873D01*
X639971Y-161039D01*
G01X650266Y-162789D02*
X657253D01*
X656598Y-160747D01*
X655506Y-159581D01*
X653978Y-158998D01*
X652449Y-159289D01*
X651139Y-160164D01*
X650266Y-162206D01*
X649829Y-163956D01*
Y-165706D01*
X650266Y-167456D01*
X651358Y-169206D01*
X652668Y-170372D01*
X654196Y-170664D01*
X655724Y-170081D01*
X657253Y-168331D01*
G01X671041Y-170664D02*
Y-153164D01*
G01X839441Y-215664D02*
Y-198164D01*
X836821Y-201664D01*
G01Y-215664D02*
X842061D01*
G01X852793Y-208373D02*
X854321Y-206331D01*
X855631Y-205164D01*
X857378Y-204581D01*
X858906Y-205164D01*
X859998Y-206331D01*
X860871Y-208081D01*
X861089Y-210122D01*
X860871Y-211873D01*
X859998Y-213623D01*
X858687Y-215081D01*
X857159Y-215664D01*
X855413Y-215081D01*
X853884Y-213331D01*
X853011Y-210706D01*
X852793Y-207789D01*
X853229Y-203998D01*
X853884Y-201955D01*
X854976Y-199914D01*
X856504Y-198456D01*
X858033Y-198164D01*
X859561Y-198747D01*
X860653Y-200206D01*
G01X869638Y-212164D02*
X870947Y-214206D01*
X872694Y-215372D01*
X874659Y-215664D01*
X876406Y-215372D01*
X878153Y-213914D01*
X879244Y-212164D01*
X879463Y-210414D01*
X879026Y-208373D01*
X877498Y-206914D01*
X875969Y-206331D01*
X874004D01*
G01X875969D02*
X877279Y-205456D01*
X878371Y-203998D01*
X878808Y-202248D01*
X878371Y-200497D01*
X877279Y-199039D01*
X875314Y-198164D01*
X873349Y-198456D01*
X871384Y-199623D01*
G01X891941Y-215664D02*
Y-198164D01*
X889321Y-201664D01*
G01Y-215664D02*
X894561D01*
G01X909004D02*
X909441Y-211873D01*
X910096Y-208664D01*
X910969Y-205747D01*
X912061Y-202539D01*
X913808Y-198164D01*
X905074D01*
G01X826324Y-170664D02*
Y-153164D01*
X831564D01*
X833311Y-154039D01*
X834621Y-156081D01*
X835058Y-158414D01*
X834621Y-160747D01*
X833529Y-162497D01*
X831564Y-163373D01*
X826324D01*
G01X852994Y-154623D02*
X851684Y-153747D01*
X850156Y-153164D01*
X848409D01*
X846444Y-154039D01*
X844916Y-155497D01*
X843824Y-157248D01*
X842951Y-160164D01*
X842732Y-162789D01*
X843169Y-165414D01*
X843824Y-167164D01*
X845134Y-168914D01*
X846663Y-170081D01*
X848191Y-170664D01*
X849719D01*
X851248Y-170081D01*
X852558Y-169206D01*
X853650Y-168040D01*
G01X867437Y-161331D02*
X868311Y-160456D01*
X868966Y-158998D01*
X869403Y-156955D01*
X868966Y-155206D01*
X868093Y-154039D01*
X866564Y-153164D01*
X860669D01*
Y-170664D01*
X867874D01*
X869403Y-169498D01*
X870276Y-167747D01*
X870713Y-165706D01*
X870276Y-163664D01*
X868966Y-161914D01*
X867437Y-161331D01*
X860669D01*
G01X876641Y-176497D02*
X889741D01*
G01X895669Y-170664D02*
Y-153164D01*
X905713Y-170664D01*
Y-153164D01*
G01X918191Y-170664D02*
X916444Y-170372D01*
X914916Y-169206D01*
X913606Y-167456D01*
X912732Y-165414D01*
X912296Y-163081D01*
Y-160747D01*
X912732Y-158414D01*
X913606Y-156372D01*
X914916Y-154623D01*
X916444Y-153456D01*
X918191Y-153164D01*
X919937Y-153456D01*
X921466Y-154623D01*
X922776Y-156372D01*
X923650Y-158414D01*
X924086Y-160747D01*
Y-163081D01*
X923650Y-165414D01*
X922776Y-167456D01*
X921466Y-169206D01*
X919937Y-170372D01*
X918191Y-170664D01*
G01X1000741Y-215664D02*
Y-198164D01*
X998121Y-201664D01*
G01Y-215664D02*
X1003361D01*
G01X969032Y-153164D02*
X974491Y-170664D01*
X979950Y-153164D01*
G01X996358Y-170664D02*
X987624D01*
Y-153164D01*
X996358D01*
G01X992864Y-161622D02*
X987624D01*
G01X1005124Y-170664D02*
Y-153164D01*
X1010583D01*
X1012329Y-154039D01*
X1013421Y-155206D01*
X1013858Y-157539D01*
X1013421Y-159873D01*
X1012111Y-161331D01*
X1010583Y-162206D01*
X1005124D01*
G01X1010583D02*
X1013858Y-170664D01*
G01X1026991Y-171247D02*
X1026554Y-170956D01*
Y-170372D01*
X1026991Y-170081D01*
X1027428Y-170372D01*
Y-170956D01*
X1026991Y-171247D01*
G01X1181308Y-198164D02*
Y-215664D01*
X1172574D01*
G01X1159878D02*
X1159441Y-211873D01*
X1158786Y-208664D01*
X1157913Y-205747D01*
X1156821Y-202539D01*
X1155074Y-198164D01*
X1163808D01*
G01X1140631Y-206914D02*
X1136264D01*
Y-212164D01*
X1137574Y-213914D01*
X1139103Y-215081D01*
X1141286Y-215664D01*
X1143469Y-215081D01*
X1144998Y-213914D01*
X1146308Y-212164D01*
X1147181Y-210122D01*
X1147618Y-207789D01*
Y-205747D01*
X1147181Y-203998D01*
X1146308Y-201955D01*
X1144998Y-200206D01*
X1143688Y-199039D01*
X1141941Y-198164D01*
X1140413D01*
X1138666Y-198747D01*
X1137356Y-199914D01*
G01X1129463Y-215664D02*
Y-198164D01*
X1119419Y-215664D01*
Y-198164D01*
G01X1111744Y-215664D02*
Y-198164D01*
X1107378D01*
X1105631Y-199039D01*
X1104321Y-200206D01*
X1103229Y-201955D01*
X1102356Y-203998D01*
X1102138Y-206914D01*
X1102356Y-209831D01*
X1103229Y-211873D01*
X1104321Y-213623D01*
X1105631Y-214789D01*
X1107378Y-215664D01*
X1111744D01*
G01X1102574Y-153164D02*
Y-170664D01*
X1111308D01*
G01X1128371D02*
Y-158998D01*
G01Y-161039D02*
X1127498Y-159873D01*
X1126187Y-159289D01*
X1124659Y-158998D01*
X1123131Y-159581D01*
X1121821Y-160747D01*
X1120947Y-162497D01*
X1120511Y-164831D01*
X1120947Y-167164D01*
X1121821Y-168914D01*
X1123131Y-170081D01*
X1124659Y-170664D01*
X1126187Y-170372D01*
X1127498Y-169498D01*
X1128371Y-168331D01*
G01X1137356Y-175914D02*
X1138666Y-176497D01*
X1140413Y-175914D01*
X1141504Y-174748D01*
X1142378Y-173289D01*
X1143687Y-168623D01*
X1146526Y-158998D01*
G01X1139539D02*
X1143687Y-168623D01*
G01X1156166Y-162789D02*
X1163153D01*
X1162498Y-160747D01*
X1161406Y-159581D01*
X1159878Y-158998D01*
X1158349Y-159289D01*
X1157039Y-160164D01*
X1156166Y-162206D01*
X1155729Y-163956D01*
Y-165706D01*
X1156166Y-167456D01*
X1157258Y-169206D01*
X1158568Y-170372D01*
X1160096Y-170664D01*
X1161624Y-170081D01*
X1163153Y-168331D01*
G01X1173884Y-170664D02*
Y-158998D01*
G01Y-161331D02*
X1174976Y-160164D01*
X1176068Y-159289D01*
X1177596Y-158998D01*
X1178687Y-159289D01*
X1179998Y-160164D01*
G01X1244688Y-170664D02*
Y-153164D01*
X1249054D01*
X1250801Y-154039D01*
X1252111Y-155206D01*
X1253203Y-156955D01*
X1254076Y-158998D01*
X1254294Y-161914D01*
X1254076Y-164831D01*
X1253203Y-166873D01*
X1252111Y-168623D01*
X1250801Y-169789D01*
X1249054Y-170664D01*
X1244688D01*
G01X1263716Y-162789D02*
X1270703D01*
X1270048Y-160747D01*
X1268956Y-159581D01*
X1267428Y-158998D01*
X1265899Y-159289D01*
X1264589Y-160164D01*
X1263716Y-162206D01*
X1263279Y-163956D01*
Y-165706D01*
X1263716Y-167456D01*
X1264808Y-169206D01*
X1266118Y-170372D01*
X1267646Y-170664D01*
X1269174Y-170081D01*
X1270703Y-168331D01*
G01X1281216Y-168623D02*
X1282308Y-169789D01*
X1283836Y-170664D01*
X1285146D01*
X1286456Y-170081D01*
X1287329Y-169206D01*
X1287766Y-168040D01*
X1287548Y-166289D01*
X1286674Y-165414D01*
X1282744Y-163664D01*
X1281871Y-161622D01*
X1282308Y-160164D01*
X1283181Y-159289D01*
X1284491Y-158998D01*
X1285801Y-159289D01*
X1287111Y-160164D01*
G01X1301991Y-158998D02*
Y-170664D01*
G01Y-154331D02*
X1301554Y-154039D01*
Y-153456D01*
X1301991Y-153164D01*
X1302428Y-153456D01*
Y-154039D01*
X1301991Y-154331D01*
G01X1316434Y-175039D02*
X1317963Y-176206D01*
X1319709Y-176497D01*
X1321237Y-176206D01*
X1322548Y-174748D01*
X1323421Y-172706D01*
Y-158998D01*
G01Y-161331D02*
X1322548Y-160164D01*
X1321237Y-159289D01*
X1319709Y-158998D01*
X1317963Y-159581D01*
X1316871Y-160747D01*
X1315997Y-162789D01*
X1315561Y-164831D01*
X1315779Y-166581D01*
X1316653Y-168623D01*
X1317963Y-170081D01*
X1319709Y-170664D01*
X1321019Y-170372D01*
X1322548Y-169206D01*
X1323421Y-168040D01*
G01X1333279Y-170664D02*
Y-158998D01*
G01Y-161914D02*
X1334153Y-160456D01*
X1335463Y-159289D01*
X1337209Y-158998D01*
X1338737Y-159289D01*
X1340048Y-160456D01*
X1340703Y-162497D01*
Y-170664D01*
G01X1351216Y-162789D02*
X1358203D01*
X1357548Y-160747D01*
X1356456Y-159581D01*
X1354928Y-158998D01*
X1353399Y-159289D01*
X1352089Y-160164D01*
X1351216Y-162206D01*
X1350779Y-163956D01*
Y-165706D01*
X1351216Y-167456D01*
X1352308Y-169206D01*
X1353618Y-170372D01*
X1355146Y-170664D01*
X1356674Y-170081D01*
X1358203Y-168331D01*
G01X1368934Y-170664D02*
Y-158998D01*
G01Y-161331D02*
X1370026Y-160164D01*
X1371118Y-159289D01*
X1372646Y-158998D01*
X1373737Y-159289D01*
X1375048Y-160164D01*
G01X1266991Y-215664D02*
X1265244Y-215372D01*
X1263716Y-214206D01*
X1262406Y-212456D01*
X1261532Y-210414D01*
X1261096Y-208081D01*
Y-205747D01*
X1261532Y-203414D01*
X1262406Y-201372D01*
X1263716Y-199623D01*
X1265244Y-198456D01*
X1266991Y-198164D01*
X1268737Y-198456D01*
X1270266Y-199623D01*
X1271576Y-201372D01*
X1272450Y-203414D01*
X1272886Y-205747D01*
Y-208081D01*
X1272450Y-210414D01*
X1271576Y-212456D01*
X1270266Y-214206D01*
X1268737Y-215372D01*
X1266991Y-215664D01*
G01X1268737Y-210997D02*
X1271358Y-215664D01*
G01X1279688Y-198164D02*
Y-210706D01*
X1280561Y-213331D01*
X1282308Y-215081D01*
X1284491Y-215664D01*
X1286674Y-215081D01*
X1288421Y-213331D01*
X1289294Y-210706D01*
Y-198164D01*
G01X1299371D02*
X1304611D01*
G01X1301991D02*
Y-215664D01*
G01X1299371D02*
X1304611D01*
G01X1314469D02*
Y-198164D01*
X1324513Y-215664D01*
Y-198164D01*
G01X1341794Y-199623D02*
X1340484Y-198747D01*
X1338956Y-198164D01*
X1337209D01*
X1335244Y-199039D01*
X1333716Y-200497D01*
X1332624Y-202248D01*
X1331751Y-205164D01*
X1331532Y-207789D01*
X1331969Y-210414D01*
X1332624Y-212164D01*
X1333934Y-213914D01*
X1335463Y-215081D01*
X1336991Y-215664D01*
X1338519D01*
X1340048Y-215081D01*
X1341358Y-214206D01*
X1342450Y-213040D01*
G01X1354491Y-215664D02*
Y-207789D01*
X1350124Y-198164D01*
G01X1358858D02*
X1354491Y-207789D01*
G01X1415691Y-198164D02*
X1413944Y-198747D01*
X1412634Y-200206D01*
X1411761Y-201955D01*
X1411106Y-204289D01*
X1410888Y-206914D01*
X1411106Y-209539D01*
X1411761Y-211873D01*
X1412634Y-213623D01*
X1413944Y-215081D01*
X1415691Y-215664D01*
X1417437Y-215081D01*
X1418748Y-213623D01*
X1419621Y-211873D01*
X1420276Y-209539D01*
X1420494Y-206914D01*
X1420276Y-204289D01*
X1419621Y-201955D01*
X1418748Y-200206D01*
X1417437Y-198747D01*
X1415691Y-198164D01*
G01X1429043Y-208373D02*
X1430571Y-206331D01*
X1431881Y-205164D01*
X1433628Y-204581D01*
X1435156Y-205164D01*
X1436248Y-206331D01*
X1437121Y-208081D01*
X1437339Y-210122D01*
X1437121Y-211873D01*
X1436248Y-213623D01*
X1434937Y-215081D01*
X1433409Y-215664D01*
X1431663Y-215081D01*
X1430134Y-213331D01*
X1429261Y-210706D01*
X1429043Y-207789D01*
X1429479Y-203998D01*
X1430134Y-201955D01*
X1431226Y-199914D01*
X1432754Y-198456D01*
X1434283Y-198164D01*
X1435811Y-198747D01*
X1436903Y-200206D01*
G01X1446761Y-216247D02*
X1454621Y-198164D01*
G01X1468191D02*
X1466444Y-198747D01*
X1465134Y-200206D01*
X1464261Y-201955D01*
X1463606Y-204289D01*
X1463388Y-206914D01*
X1463606Y-209539D01*
X1464261Y-211873D01*
X1465134Y-213623D01*
X1466444Y-215081D01*
X1468191Y-215664D01*
X1469937Y-215081D01*
X1471248Y-213623D01*
X1472121Y-211873D01*
X1472776Y-209539D01*
X1472994Y-206914D01*
X1472776Y-204289D01*
X1472121Y-201955D01*
X1471248Y-200206D01*
X1469937Y-198747D01*
X1468191Y-198164D01*
G01X1481979Y-213623D02*
X1483508Y-215081D01*
X1485254Y-215664D01*
X1487001Y-215081D01*
X1488529Y-213331D01*
X1489621Y-210706D01*
X1490058Y-208081D01*
Y-204873D01*
X1489621Y-202248D01*
X1488529Y-199914D01*
X1487219Y-198747D01*
X1485691Y-198164D01*
X1483944Y-198747D01*
X1482634Y-199914D01*
X1481761Y-201664D01*
X1481324Y-203998D01*
X1481761Y-206039D01*
X1482853Y-208081D01*
X1484163Y-209248D01*
X1485691Y-209539D01*
X1487437Y-208956D01*
X1488748Y-207497D01*
X1490058Y-204873D01*
G01X1499261Y-216247D02*
X1507121Y-198164D01*
G01X1516543Y-201081D02*
X1517853Y-199331D01*
X1519381Y-198456D01*
X1521128Y-198164D01*
X1523311Y-198747D01*
X1524839Y-200206D01*
X1525276Y-201955D01*
X1525058Y-203706D01*
X1524184Y-205164D01*
X1519818Y-208081D01*
X1517853Y-210122D01*
X1516543Y-213040D01*
X1516106Y-215664D01*
X1525276D01*
G01X1538191Y-198164D02*
X1536444Y-198747D01*
X1535134Y-200206D01*
X1534261Y-201955D01*
X1533606Y-204289D01*
X1533388Y-206914D01*
X1533606Y-209539D01*
X1534261Y-211873D01*
X1535134Y-213623D01*
X1536444Y-215081D01*
X1538191Y-215664D01*
X1539937Y-215081D01*
X1541248Y-213623D01*
X1542121Y-211873D01*
X1542776Y-209539D01*
X1542994Y-206914D01*
X1542776Y-204289D01*
X1542121Y-201955D01*
X1541248Y-200206D01*
X1539937Y-198747D01*
X1538191Y-198164D01*
G01X1555691Y-215664D02*
Y-198164D01*
X1553071Y-201664D01*
G01Y-215664D02*
X1558311D01*
G01X1572754D02*
X1573191Y-211873D01*
X1573846Y-208664D01*
X1574719Y-205747D01*
X1575811Y-202539D01*
X1577558Y-198164D01*
X1568824D01*
G01X1463388Y-170664D02*
Y-153164D01*
X1467754D01*
X1469501Y-154039D01*
X1470811Y-155206D01*
X1471903Y-156955D01*
X1472776Y-158998D01*
X1472994Y-161914D01*
X1472776Y-164831D01*
X1471903Y-166873D01*
X1470811Y-168623D01*
X1469501Y-169789D01*
X1467754Y-170664D01*
X1463388D01*
G01X1489621D02*
Y-158998D01*
G01Y-161039D02*
X1488748Y-159873D01*
X1487437Y-159289D01*
X1485909Y-158998D01*
X1484381Y-159581D01*
X1483071Y-160747D01*
X1482197Y-162497D01*
X1481761Y-164831D01*
X1482197Y-167164D01*
X1483071Y-168914D01*
X1484381Y-170081D01*
X1485909Y-170664D01*
X1487437Y-170372D01*
X1488748Y-169498D01*
X1489621Y-168331D01*
G01X1503191Y-153164D02*
Y-170664D01*
G01X1500134Y-158998D02*
X1506248D01*
G01X1517416Y-162789D02*
X1524403D01*
X1523748Y-160747D01*
X1522656Y-159581D01*
X1521128Y-158998D01*
X1519599Y-159289D01*
X1518289Y-160164D01*
X1517416Y-162206D01*
X1516979Y-163956D01*
Y-165706D01*
X1517416Y-167456D01*
X1518508Y-169206D01*
X1519818Y-170372D01*
X1521346Y-170664D01*
X1522874Y-170081D01*
X1524403Y-168331D01*
M02*
